G04 ================== begin FILE IDENTIFICATION RECORD ==================*
G04 Layout Name:  D:/<user>/Wistron_project/16316-1/gbr-0621/16316-1.brd*
G04 Film Name:    L6*
G04 File Format:  Gerber RS274X*
G04 File Origin:  Cadence Allegro 16.5-S056*
G04 Origin Date:  Wed Jun 21 09:32:13 2017*
G04 *
G04 Layer:  VIA CLASS/L6*
G04 Layer:  PIN/L6*
G04 Layer:  ETCH/L6*
G04 Layer:  DRAWING FORMAT/LAYER_PCB_STORY*
G04 Layer:  DRAWING FORMAT/LAYER_L6*
G04 *
G04 Offset:    (0.00 0.00)*
G04 Mirror:    No*
G04 Mode:      Positive*
G04 Rotation:  0*
G04 FullContactRelief:  No*
G04 UndefLineWidth:     6.00*
G04 ================== end FILE IDENTIFICATION RECORD ====================*
%FSLAX35Y35*MOIN*%
%IR0*IPPOS*OFA0.00000B0.00000*MIA0B0*SFA1.00000B1.00000*%
%ADD11C,.02*%
%ADD13C,.03*%
%ADD12C,.034*%
%ADD14C,.018*%
%ADD10C,.028*%
%ADD15C,.029*%
%ADD16C,.01*%
%ADD17C,.04*%
%ADD18C,.004*%
%ADD19C,.006*%
%ADD20C,.005*%
%ADD21C,.0035*%
%ADD22C,.0055*%
%ADD25C,.03004*%
%ADD23C,.05204*%
%ADD24C,.04404*%
G75*
%LPD*%
G75*
G36*
G01X443151Y493059D02*
X476035Y498319D01*
G03X495140Y520723I-3584J22404D01*
G01Y562992D01*
G02X500010Y567862I4870J0D01*
G01X818898D01*
G02X823768Y562992I0J-4870D01*
G01Y7874D01*
G02X818898Y3004I-4870J0D01*
G01X168082D01*
Y8000D01*
X344155D01*
G03X347185I1515J2237D01*
G01X358328D01*
G03X361358I1515J2237D01*
G01X372501D01*
G03X375531I1515J2237D01*
G01X386674D01*
G03X389704I1515J2237D01*
G01X400848D01*
G03X403878I1515J2237D01*
G01X415021D01*
G03X418051I1515J2237D01*
G01X429194D01*
G03X432224I1515J2237D01*
G01X443367D01*
G03X446397I1515J2237D01*
G01X457540D01*
G03X460570I1515J2237D01*
G01X471714D01*
G03X474744I1515J2237D01*
G01X485887D01*
G03X488917I1515J2237D01*
G01X500060D01*
G03X503090I1515J2237D01*
G01X514233D01*
G03X517263I1515J2237D01*
G01X528407D01*
G03X531437I1515J2237D01*
G01X542580D01*
G03X545610I1515J2237D01*
G01X556753D01*
G03X559783I1515J2237D01*
G01X570926D01*
G03X573956I1515J2237D01*
G01X585099D01*
G03X588129I1515J2237D01*
G01X714233D01*
G03X717263I1515J2237D01*
G01X728406D01*
G03X731436I1515J2237D01*
G01X742579D01*
G03X745609I1515J2237D01*
G01X756752D01*
G03X759782I1515J2237D01*
G01X818772D01*
Y562866D01*
X500136D01*
Y520723D01*
G02X476824Y493386I-27685J1D01*
G01X443548Y488063D01*
X383223D01*
X349967Y493383D01*
G02X326656Y520719I4374J27337D01*
G01Y563116D01*
X7896D01*
X7750Y562970D01*
Y562762D01*
X7896Y562616D01*
X8000D01*
Y8000D01*
X102995D01*
Y3004D01*
X7874D01*
G02X3004Y7874I0J4870D01*
G01Y562992D01*
G02X7874Y567862I4870J0D01*
G01X326783D01*
G02X331650Y563117I-1J-4870D01*
G01Y562616D01*
X331652D01*
Y520719D01*
G03X350756Y498316I22689J1D01*
G01X383620Y493059D01*
X443151D01*
G37*
G36*
G01X163600Y333694D02*
Y360700D01*
X164100Y361200D01*
X187400D01*
X190500Y358100D01*
Y319500D01*
X209700Y300300D01*
X273800D01*
X276700Y297400D01*
Y274700D01*
X273800Y271800D01*
X167900D01*
X163600Y276100D01*
Y329854D01*
G03Y333694I-1078J1920D01*
G37*
G36*
G01X570975Y292025D02*
X568500Y294500D01*
Y300900D01*
X582700Y315100D01*
Y371395D01*
X570498Y383598D01*
Y390398D01*
X571574Y391474D01*
X591687D01*
G02X592073Y390970I0J-400D01*
G03X596327I2127J-570D01*
G02X596713Y391474I386J104D01*
G01X607526D01*
X613000Y386000D01*
Y359435D01*
G02X612554Y359037I-400J-1D01*
G03Y354663I-254J-2187D01*
G02X613000Y354265I46J-397D01*
G01Y338680D01*
G02X612316Y338398I-400J0D01*
G03Y335302I-1566J-1548D01*
G02X613000Y335020I284J-282D01*
G01Y293500D01*
X611525Y292025D01*
X570975D01*
G37*
G36*
G01X716044Y95300D02*
X715935Y95408D01*
Y95409D01*
G03X712548Y96775I-3301J-3303D01*
G03X711787Y98092I-2170J-376D01*
G02Y98706I255J307D01*
G03X708223Y100852I-1409J1693D01*
G02X707549Y100651I-391J82D01*
G01X707100Y101100D01*
X626400D01*
X625100Y102400D01*
Y163458D01*
X631650Y170008D01*
Y181450D01*
X631550Y181550D01*
Y184450D01*
X622900Y193100D01*
Y210750D01*
X626000Y213850D01*
Y225700D01*
X632300Y232000D01*
X633910D01*
G03X634090I90J2200D01*
G01X647700D01*
X648500Y231200D01*
Y183000D01*
X643000Y177500D01*
Y173300D01*
X639000Y169300D01*
X638931Y169292D01*
G03X637616Y167977I177J-1492D01*
G01X637608Y167908D01*
X637300Y167600D01*
Y165000D01*
X634400Y162100D01*
Y134100D01*
X634394Y134076D01*
G03Y133354I1458J-361D01*
G01X634400Y133330D01*
Y109300D01*
X638100Y105600D01*
X705200D01*
X708207Y108607D01*
X708242Y108622D01*
G03X709029Y109409I-593J1380D01*
G01X709044Y109444D01*
X712000Y112400D01*
Y113800D01*
X712900Y114700D01*
X724500D01*
X725200Y115400D01*
Y117500D01*
X724400Y118300D01*
X707300D01*
X706500Y119100D01*
Y126700D01*
X707300Y127500D01*
X715100D01*
X715683Y128083D01*
G02X716251Y128080I283J-283D01*
G03X716264Y130199I1071J1053D01*
G02X715700Y130200I-281J284D01*
G01X714700Y131200D01*
X712798D01*
G02X712425Y131744I0J400D01*
G03X709534Y132477I-1402J539D01*
G02X708854Y132246I-397J52D01*
G01X707600Y133500D01*
Y139834D01*
G02X707973Y140233I400J0D01*
G03X709117Y140889I-99J1499D01*
G02X709780I331J-224D01*
G03X712267Y140890I1243J843D01*
G02X712929I331J-224D01*
G03X715416Y140889I1244J842D01*
G02X716078I331J-224D01*
G03X718566I1244J842D01*
G02X719228Y140890I331J-224D01*
G03Y142574I1244J842D01*
G02X718566Y142573I-331J224D01*
G03X718165Y142974I-1243J-842D01*
G02Y143637I224J332D01*
G03X716078Y145722I-843J1243D01*
G02X715416I-331J224D01*
G03X713329Y143637I-1244J-842D01*
G02Y142975I-224J-331D01*
G03X712929Y142574I844J-1242D01*
G02X712267I-331J224D01*
G03X709780Y142575I-1244J-842D01*
G02X709117I-332J224D01*
G03X708684Y142997I-1243J-843D01*
G02X708617Y143617I215J337D01*
G01X709048Y144048D01*
X709482D01*
X711602Y146168D01*
Y146602D01*
X711900Y146900D01*
Y171200D01*
X712300Y171600D01*
X715000D01*
X715700Y172300D01*
Y174000D01*
X715000Y174700D01*
X714466D01*
X714448Y174703D01*
G03X713896I-276J-1476D01*
G01X713878Y174700D01*
X711322D01*
X711304Y174704D01*
G03X710742I-281J-1476D01*
G01X710724Y174700D01*
X708400D01*
X707650Y175450D01*
Y186283D01*
X707102Y186832D01*
X702584Y191350D01*
X701023D01*
X700100Y192272D01*
Y196200D01*
X700300Y196400D01*
X726700D01*
X727900Y195200D01*
Y193882D01*
G02X727347Y193513I-400J0D01*
G03Y190739I-577J-1387D01*
G02X727900Y190370I153J-369D01*
G01Y187583D01*
G02X727347Y187214I-400J0D01*
G03Y184440I-577J-1387D01*
G02X727900Y184071I153J-369D01*
G01Y181284D01*
G02X727347Y180915I-400J0D01*
G03Y178141I-577J-1387D01*
G02X727900Y177772I153J-369D01*
G01Y174985D01*
G02X727347Y174616I-400J0D01*
G03Y171842I-577J-1387D01*
G02X727900Y171473I153J-369D01*
G01Y170800D01*
X731577Y167123D01*
X731571Y167033D01*
G03X734556Y166718I1498J-103D01*
G01X734580Y166890D01*
X746770D01*
X763820Y183940D01*
X787010D01*
X791330Y179620D01*
Y112561D01*
X774069Y95300D01*
X716044D01*
G37*
G36*
G01X623400Y283600D02*
X619840Y287160D01*
X619962Y287301D01*
G03X617555Y290817I-1662J1444D01*
G02X617020Y291194I-135J377D01*
G01Y325205D01*
G02X617555Y325582I400J0D01*
G03Y329726I745J2072D01*
G02X617020Y330103I-135J377D01*
G01Y398980D01*
X630405Y412364D01*
X630431Y412378D01*
G03X631346Y413293I-1031J1946D01*
G01X631360Y413319D01*
X649241Y431200D01*
X660100D01*
X660801Y430499D01*
Y403679D01*
G02X660124Y403390I-400J0D01*
G03Y400210I-1523J-1590D01*
G02X660801Y399921I277J-289D01*
G01Y398271D01*
X650182Y387652D01*
Y291582D01*
X642200Y283600D01*
X623400D01*
G37*
G36*
G01X657610Y106490D02*
X656200Y107900D01*
Y114080D01*
X656960Y114840D01*
X686440D01*
X687200Y115600D01*
X690600D01*
X693800Y118800D01*
Y127000D01*
X693750Y127050D01*
Y129850D01*
X692900Y130700D01*
X691000D01*
X687700Y127400D01*
X686332D01*
X686301Y127410D01*
G03X685353I-474J-1425D01*
G01X685322Y127400D01*
X683183D01*
X683152Y127410D01*
G03X682204I-474J-1425D01*
G01X682173Y127400D01*
X680033D01*
X680002Y127410D01*
G03X679054I-474J-1425D01*
G01X679023Y127400D01*
X676883D01*
X676852Y127410D01*
G03X675904I-474J-1425D01*
G01X675873Y127400D01*
X673734D01*
X673703Y127410D01*
G03X672755I-474J-1425D01*
G01X672724Y127400D01*
X670584D01*
X670553Y127410D01*
G03X669605I-474J-1425D01*
G01X669574Y127400D01*
X667431D01*
X667400Y127410D01*
G03X666428Y127400I-471J-1426D01*
G01X666400D01*
X665600Y128200D01*
Y133606D01*
X666400Y134406D01*
X675285D01*
G03X677473I1094J1029D01*
G01X681585D01*
G03X683773I1094J1029D01*
G01X687884D01*
G03X690072I1094J1029D01*
G01X691026D01*
G03X693167Y134350I1098J1025D01*
G01X693225Y134406D01*
X693586D01*
X696646Y131346D01*
Y116154D01*
X701100Y111700D01*
Y107890D01*
X699700Y106490D01*
X657610D01*
G37*
G36*
G01X636350Y108550D02*
X635202Y109698D01*
Y161502D01*
X642874Y169174D01*
X643683D01*
G03X646081I1199J904D01*
G01X646832D01*
G03X649230I1199J904D01*
G01X653131D01*
G03X655529I1199J904D01*
G01X659430D01*
G03X661398Y168788I1199J904D01*
G01X661532Y168868D01*
X662568Y167832D01*
X662488Y167698D01*
G03X664676Y165724I1290J-770D01*
G01X668959Y161441D01*
Y158482D01*
G03Y156478I1119J-1002D01*
G01Y155332D01*
G03Y153328I1119J-1002D01*
G01Y152183D01*
G03Y150179I1119J-1002D01*
G01Y149030D01*
G03X668836Y148872I1121J-1000D01*
G02X668173I-331J224D01*
G03X666160Y146741I-1244J-841D01*
G02X666171Y146060I-204J-344D01*
G03X665749Y145639I757J-1180D01*
G02X665069Y145651I-336J216D01*
G03X665067Y144113I-1291J-767D01*
G02X665748Y144124I344J-205D01*
G03X666816Y143482I1181J755D01*
G02X667000Y143283I-16J-199D01*
G01Y140278D01*
G02X666815Y140079I-200J0D01*
G03X665685Y139424I113J-1498D01*
G02X665023Y139425I-331J225D01*
G03X662535Y139427I-1245J-841D01*
G02X661872I-331J224D01*
G03X661472Y139827I-1243J-843D01*
G02Y140489I225J331D01*
G03X659786I-843J1243D01*
G02Y139827I-225J-331D01*
G03X661872Y137741I843J-1243D01*
G02X662535I331J-224D01*
G03X662938Y137339I1243J843D01*
G02Y136676I-224J-331D01*
G03X662444Y134741I840J-1245D01*
G01X662511Y134611D01*
X659000Y131100D01*
X656200D01*
X655900Y131400D01*
Y147200D01*
X659030Y150330D01*
Y155312D01*
X655242Y159100D01*
X644300D01*
X643300Y158100D01*
Y156300D01*
X646400Y153200D01*
Y109500D01*
X645450Y108550D01*
X636350D01*
G37*
G36*
G01X679600Y140500D02*
X675205Y144895D01*
Y157545D01*
X674539Y158211D01*
X674526Y158234D01*
G03X673982Y158778I-1299J-755D01*
G01X673959Y158791D01*
X665850Y166900D01*
Y183550D01*
X661600Y187800D01*
X652917D01*
G02X652552Y188363I0J400D01*
G03X652024Y190219I-1371J613D01*
G02Y190882I224J332D01*
G03X650090Y193158I-844J1243D01*
G02X649400Y193433I-290J275D01*
G01Y245860D01*
X641953Y253307D01*
Y280300D01*
X668191Y306538D01*
Y344991D01*
X694582Y371382D01*
G03X695418Y372218I-1082J1918D01*
G01X697300Y374100D01*
X710300D01*
X719900Y383700D01*
X743994D01*
X748822Y378872D01*
Y329444D01*
X696232Y276854D01*
Y276852D01*
X690456Y271077D01*
Y242464D01*
X690326Y242416D01*
G03X689323Y241654I775J-2061D01*
G02X688677I-323J236D01*
G03X685123I-1777J-1300D01*
G02X684477I-323J236D01*
G03X680914Y241641I-1777J-1300D01*
G02X680268Y241637I-324J234D01*
G03X680286Y239037I-1768J-1312D01*
G02X680932Y239041I324J-234D01*
G03X684477Y239054I1768J1313D01*
G02X685123I323J-236D01*
G03X688677I1777J1300D01*
G02X689323I323J-236D01*
G03X690326Y238292I1778J1299D01*
G01X690456Y238244D01*
Y218652D01*
X686166Y214362D01*
Y212645D01*
X698742Y200069D01*
Y194025D01*
G02X698359Y193626I-400J0D01*
G03X699535Y191113I66J-1501D01*
G02X700113Y191126I295J-270D01*
G01X700691Y190548D01*
X702252D01*
X706300Y186500D01*
Y172100D01*
X706800Y171600D01*
X710000D01*
X710800Y170800D01*
Y146500D01*
X709150Y144850D01*
X708650D01*
X704300Y140500D01*
X679600D01*
G37*
%LPC*%
G75*
G36*
G01X240845Y287858D02*
G03Y288141I-141J142D01*
G02X243957Y288142I1555J1559D01*
G03Y287859I141J-142D01*
G02X240845Y287858I-1555J-1559D01*
G37*
G36*
G01X207197Y280792D02*
G03X207406Y280600I200J8D01*
G02X205300Y278310I94J-2200D01*
G03X205091Y278502I-200J-8D01*
G02X207197Y280792I-94J2200D01*
G37*
G36*
G01X224606Y276888D02*
G03X224341Y276784I-81J-183D01*
G02X223214Y279670I-2021J874D01*
G03X223479Y279774I81J183D01*
G02X224606Y276888I2021J-874D01*
G37*
G36*
G01X268323Y278918D02*
G03X268898Y278785I348J197D01*
G02X268226Y275886I1245J-1816D01*
G03X267651Y276019I-348J-197D01*
G02X264880Y276247I-1245J1816D01*
G03X264326I-277J-288D01*
G02Y279423I-1526J1588D01*
G03X264880I277J288D01*
G02X268323Y278918I1526J-1588D01*
G37*
G36*
G01X595809Y355307D02*
G03Y354693I255J-307D01*
G02X592991I-1409J-1693D01*
G03Y355307I-255J307D01*
G02X595809I1409J1693D01*
G37*
G36*
G01X591701Y336493D02*
G03X591724Y335939I300J-265D01*
G02X588549Y335807I-1524J-1589D01*
G03X588526Y336361I-300J265D01*
G02X591701Y336493I1524J1589D01*
G37*
G36*
G01X598859Y323057D02*
G03Y322443I255J-307D01*
G02X596041I-1409J-1693D01*
G03Y323057I-255J307D01*
G02X598859I1409J1693D01*
G37*
G36*
G01X775077Y118010D02*
G03X774523I-277J-289D01*
G02Y121190I-1523J1590D01*
G03X775077I277J289D01*
G02Y118010I1523J-1590D01*
G37*
G36*
G01X735850Y109009D02*
G03X735309Y108969I-249J-313D01*
G02X735147Y111171I-1097J1026D01*
G03X735688Y111211I249J313D01*
G02X735850Y109009I1097J-1026D01*
G37*
G36*
G01X718654Y109280D02*
G03X719035Y108783I388J-97D01*
G02X717553Y107647I-25J-1502D01*
G03X717172Y108144I-388J97D01*
G02X718654Y109280I25J1502D01*
G37*
G36*
G01X769721Y108210D02*
G03X769734Y107927I148J-135D01*
G02X766629Y107790I-1484J-1627D01*
G03X766616Y108073I-148J135D01*
G02X769721Y108210I1484J1627D01*
G37*
G36*
G01X712266Y178684D02*
G02X710180Y180770I-1244J842D01*
G03Y181432I-224J331D01*
G02X710179Y183919I842J1244D01*
G03Y184582I-224J331D01*
G02X710181Y187070I843J1243D01*
G03X710182Y187732I-224J331D01*
G02X710181Y190219I842J1244D01*
G03Y190882I-224J332D01*
G02X711867I843J1243D01*
G03Y190219I224J-331D01*
G02X711865Y187731I-843J-1243D01*
G03X711864Y187069I224J-331D01*
G02X711865Y184582I-842J-1244D01*
G03Y183919I224J-331D01*
G02X711864Y181432I-843J-1243D01*
G03Y180770I224J-331D01*
G02X712266Y180368I-842J-1244D01*
G03X712928I331J224D01*
G02Y178684I1244J-842D01*
G03X712266I-331J-224D01*
G37*
G36*
G01X715416Y162936D02*
G02Y164620I-1244J842D01*
G03X716078I331J224D01*
G02X716480Y165022I1244J-842D01*
G03Y165684I-224J331D01*
G02X718565Y167771I842J1244D01*
G03X719228I332J224D01*
G02Y166085I1243J-843D01*
G03X718565I-331J-224D01*
G02X718164Y165684I-1243J842D01*
G03Y165022I224J-331D01*
G02X716078Y162936I-842J-1244D01*
G03X715416I-331J-224D01*
G37*
G36*
G01Y156637D02*
G02Y158321I-1244J842D01*
G03X716078I331J224D01*
G02Y156637I1244J-842D01*
G03X715416I-331J-224D01*
G37*
G36*
G01X730763Y155574D02*
G02X729079I-842J-1244D01*
G03Y156236I-224J331D01*
G02X729078Y158723I842J1244D01*
G03Y159386I-224J331D01*
G02X729079Y161873I843J1243D01*
G03Y162535I-224J331D01*
G02X728677Y162937I842J1244D01*
G03X728015I-331J-224D01*
G02X725929Y165023I-1244J842D01*
G03Y165686I-224J331D01*
G02X727612I842J1244D01*
G03Y165023I224J-331D01*
G02X728015Y164621I-840J-1245D01*
G03X728677I331J224D01*
G02X730763Y162535I1244J-842D01*
G03Y161873I224J-331D01*
G02X730764Y159386I-842J-1244D01*
G03Y158723I224J-331D01*
G02X730763Y156236I-843J-1243D01*
G03Y155574I224J-331D01*
G37*
G36*
G01X715416Y150338D02*
G02Y152022I-1244J842D01*
G03X716078I331J224D01*
G02Y150338I1244J-842D01*
G03X715416I-331J-224D01*
G37*
G36*
G01X741517Y136100D02*
G02X740308Y135022I237J-1483D01*
G03X739859Y135525I-385J108D01*
G02X741068Y136603I-237J1483D01*
G03X741517Y136100I385J-108D01*
G37*
G36*
G01X724866Y121992D02*
G02X724865Y123677I-1244J842D01*
G03X725527I331J224D01*
G02X728015I1244J-842D01*
G03X728677Y123676I331J224D01*
G02X729079Y124078I1244J-842D01*
G03Y124740I-224J331D01*
G02Y127228I842J1244D01*
G03Y127890I-224J331D01*
G02X729078Y130377I842J1244D01*
G03Y131040I-224J331D01*
G02X729079Y133527I843J1243D01*
G03Y134189I-224J331D01*
G02X729078Y136676I842J1244D01*
G03Y137339I-224J332D01*
G02X729079Y139826I843J1243D01*
G03Y140488I-224J331D01*
G02Y142976I842J1244D01*
G03Y143638I-224J331D01*
G02X729078Y146125I842J1244D01*
G03Y146788I-224J332D01*
G02X730764I843J1243D01*
G03Y146125I224J-331D01*
G02X730763Y143638I-843J-1243D01*
G03Y142976I224J-331D01*
G02Y140488I-842J-1244D01*
G03Y139826I224J-331D01*
G02X730764Y137339I-842J-1244D01*
G03Y136676I224J-331D01*
G02X730763Y134189I-843J-1243D01*
G03Y133527I224J-331D01*
G02X730764Y131040I-842J-1244D01*
G03Y130377I224J-331D01*
G02X730763Y127890I-843J-1243D01*
G03Y127228I224J-331D01*
G02Y124740I-842J-1244D01*
G03Y124078I224J-331D01*
G02X728677Y121992I-842J-1244D01*
G03X728015Y121993I-331J-224D01*
G02X725528Y121992I-1244J842D01*
G03X724866I-331J-224D01*
G37*
G36*
G01X736599Y107427D02*
G02X736560Y105678I1201J-902D01*
G03X735910Y105693I-330J-226D01*
G02X735949Y107442I-1201J902D01*
G03X736599Y107427I330J226D01*
G37*
G36*
G01X629447Y379944D02*
G03X628833I-307J-255D01*
G02Y382762I-1693J1409D01*
G03X629447I307J255D01*
G02Y379944I1693J-1409D01*
G37*
G36*
G01X639130Y364419D02*
G03Y363881I296J-269D01*
G02X635870I-1630J-1481D01*
G03Y364419I-296J269D01*
G02X639130I1630J1481D01*
G37*
G36*
G01X634400Y332842D02*
G03Y332312I300J-265D01*
G02X631100I-1650J-1458D01*
G03Y332842I-300J265D01*
G02X634400I1650J1458D01*
G37*
G36*
G01Y294183D02*
G03Y293653I300J-265D01*
G02X631100I-1650J-1458D01*
G03Y294183I-300J265D01*
G02X634400I1650J1458D01*
G37*
G36*
G01X635220Y390209D02*
G02X635199Y387935I2330J-1159D01*
G03X634480Y387941I-361J-172D01*
G02X634501Y390215I-2330J1159D01*
G03X635220Y390209I361J172D01*
G37*
G36*
G01X662535Y161473D02*
G02Y159786I1243J-843D01*
G03X661873I-331J-224D01*
G02Y161473I-1243J844D01*
G03X662535I331J224D01*
G37*
G36*
G01X664621Y152425D02*
G02X662936Y152424I-842J-1244D01*
G03Y153086I-224J331D01*
G02X664621Y153087I842J1244D01*
G03Y152425I224J-331D01*
G37*
G36*
G01X734163Y333920D02*
G03Y333280I240J-320D01*
G02X731037I-1563J-2080D01*
G03Y333920I-240J320D01*
G02Y338080I1563J2080D01*
G03Y338720I-240J320D01*
G02Y342880I1563J2080D01*
G03Y343520I-240J320D01*
G02Y347680I1563J2080D01*
G03Y348320I-240J320D01*
G02Y352480I1563J2080D01*
G03Y353120I-240J320D01*
G02X734163I1563J2080D01*
G03Y352480I240J-320D01*
G02Y348320I-1563J-2080D01*
G03Y347680I240J-320D01*
G02X734680Y347163I-1563J-2080D01*
G03X735320I320J240D01*
G02X739480I2080J-1563D01*
G03X740120I320J240D01*
G02X743763Y343520I2080J-1563D01*
G03Y342880I240J-320D01*
G02X740120Y339237I-1563J-2080D01*
G03X739480I-320J-240D01*
G02X735320I-2080J1563D01*
G03X734680I-320J-240D01*
G02X734163Y338720I-2080J1563D01*
G03Y338080I240J-320D01*
G02Y333920I-1563J-2080D01*
G37*
G36*
G01X703820Y304737D02*
G03X703180I-320J-240D01*
G02X699537Y308380I-2080J1563D01*
G03Y309020I-240J320D01*
G02Y313180I1563J2080D01*
G03Y313820I-240J320D01*
G02X703180Y317463I1563J2080D01*
G03X703820I320J240D01*
G02X707463Y313820I2080J-1563D01*
G03Y313180I240J-320D01*
G02Y309020I-1563J-2080D01*
G03Y308380I240J-320D01*
G02X703820Y304737I-1563J-2080D01*
G37*
G36*
G01X677420D02*
G03X676780I-320J-240D01*
G02X673137Y308380I-2080J1563D01*
G03Y309020I-240J320D01*
G02Y313180I1563J2080D01*
G03Y313820I-240J320D01*
G02X676780Y317463I1563J2080D01*
G03X677420I320J240D01*
G02X681063Y313820I2080J-1563D01*
G03Y313180I240J-320D01*
G02Y309020I-1563J-2080D01*
G03Y308380I240J-320D01*
G02X677420Y304737I-1563J-2080D01*
G37*
G36*
G01X664686Y251172D02*
G03X664671Y250634I288J-277D01*
G02X661414Y250728I-1671J-1434D01*
G03X661429Y251266I-288J277D01*
G02X664686Y251172I1671J1434D01*
G37*
G36*
G01X665289Y235232D02*
G03X665896Y235137I343J205D01*
G02X665464Y232354I1457J-1651D01*
G03X664857Y232449I-343J-205D01*
G02X661911Y235722I-1457J1651D01*
G03X661880Y236337I-270J295D01*
G02X664689Y236478I1320J1763D01*
G03X664720Y235863I270J-295D01*
G02X665289Y235232I-1320J-1763D01*
G37*
G36*
G01X670361Y282228D02*
G02X668164Y282386I-1235J-1823D01*
G03X668214Y283077I-174J360D01*
G02X670411Y282919I1235J1823D01*
G03X670361Y282228I174J-360D01*
G37*
G36*
G01X686668Y199668D02*
G02X684984I-842J-1244D01*
G03Y200330I-224J331D01*
G02X686668I842J1244D01*
G03Y199668I224J-331D01*
G37*
G36*
G01X677621Y197582D02*
G02X675535Y199668I-1244J842D01*
G03Y200330I-224J331D01*
G02X675534Y202817I842J1244D01*
G03Y203480I-224J331D01*
G02X677220I843J1243D01*
G03Y202817I224J-332D01*
G02X677219Y200330I-843J-1243D01*
G03Y199668I224J-331D01*
G02X677621Y199266I-842J-1244D01*
G03X678283I331J224D01*
G02Y197582I1244J-842D01*
G03X677621I-331J-224D01*
G37*
G36*
G01X693369D02*
G02X693368Y199266I-1244J841D01*
G03X694031I331J224D01*
G02X694032Y197582I1244J-841D01*
G03X693369I-331J-224D01*
G37*
G36*
G01X658723Y191282D02*
G02Y192968I-1243J843D01*
G03X659386I332J224D01*
G02X661873Y192967I1243J-843D01*
G03X662535I331J224D01*
G02X665023I1244J-842D01*
G03X665685I331J224D01*
G02X668172Y192968I1244J-842D01*
G03X668835I331J224D01*
G02Y191282I1243J-843D01*
G03X668172I-332J-224D01*
G02X665685Y191283I-1243J843D01*
G03X665023I-331J-224D01*
G02X662535I-1244J842D01*
G03X661873I-331J-224D01*
G02X659386Y191282I-1244J842D01*
G03X658723I-331J-224D01*
G37*
G36*
G01X702418Y180770D02*
G02X700732I-843J-1243D01*
G03Y181433I-224J331D01*
G02X700734Y183920I843J1243D01*
G03Y184583I-224J331D01*
G02X702416I841J1244D01*
G03Y183920I224J-331D01*
G02X702418Y181433I-841J-1244D01*
G03Y180770I224J-331D01*
G37*
G36*
G01X692969D02*
G02X691283I-843J-1243D01*
G03Y181433I-224J331D01*
G02X691285Y183920I843J1243D01*
G03Y184583I-224J331D01*
G02X692967I841J1244D01*
G03Y183920I224J-331D01*
G02X692969Y181433I-841J-1244D01*
G03Y180770I224J-331D01*
G37*
G36*
G01X683518D02*
G02X681835I-841J-1244D01*
G03Y181433I-224J331D01*
G02X681433Y181836I843J1243D01*
G03X680770I-331J-224D01*
G02X678284Y181835I-1243J843D01*
G03X677622I-331J-224D01*
G02Y183522I-1243J844D01*
G03X678284I331J224D01*
G02X680771Y183520I1243J-843D01*
G03X681434I331J224D01*
G02X681834Y183920I1243J-843D01*
G03Y184582I-224J331D01*
G02X681833Y187069I842J1244D01*
G03Y187732I-224J331D01*
G02X681433Y188132I843J1243D01*
G03X680770I-331J-224D01*
G02Y189818I-1243J843D01*
G03X681433I332J224D01*
G02X681834Y190219I1243J-842D01*
G03X681835Y190881I-224J331D01*
G02X683920Y192968I842J1244D01*
G03X684583I332J224D01*
G02X687070Y192967I1243J-843D01*
G03X687732I331J224D01*
G02X690219Y192968I1244J-842D01*
G03X690882I332J224D01*
G02Y191282I1243J-843D01*
G03X690219I-331J-224D01*
G02X687732Y191283I-1243J843D01*
G03X687070I-331J-224D01*
G02X684583Y191282I-1244J842D01*
G03X683920I-331J-224D01*
G02X683519Y190881I-1243J842D01*
G03X683518Y190219I224J-331D01*
G02X683519Y187732I-842J-1244D01*
G03Y187069I224J-331D01*
G02Y184583I-843J-1243D01*
G03Y183921I224J-331D01*
G02X683518Y181433I-842J-1244D01*
G03Y180770I224J-331D01*
G37*
G36*
G01X671322Y166087D02*
G02X669236Y168172I-1244J841D01*
G03Y168834I-224J331D01*
G02X669235Y171321I842J1244D01*
G03Y171984I-224J331D01*
G02X671322Y174069I843J1243D01*
G03X671985I331J224D01*
G02Y172386I1244J-841D01*
G03X671322I-331J-224D01*
G02X670921Y171984I-1245J841D01*
G03Y171321I224J-331D01*
G02X670920Y168834I-843J-1243D01*
G03Y168172I224J-331D01*
G02X671322Y167770I-842J-1244D01*
G03X671985I331J224D01*
G02Y166087I1244J-842D01*
G03X671322I-331J-224D01*
G37*
G54D25*
X634169Y166500D03*
X637343Y171335D03*
Y174835D03*
X640931Y181102D03*
X646594Y210875D03*
X640584Y194127D03*
X640509Y177600D03*
X722673Y105444D03*
X726100Y107200D03*
X731000Y106315D03*
X725943Y100147D03*
X710517Y106823D03*
X711023Y122834D03*
X717322D03*
X743452Y151815D03*
X720472Y173228D03*
Y148031D03*
Y160629D03*
Y154330D03*
Y135433D03*
X739952Y120649D03*
X740952Y126815D03*
X743100Y114700D03*
X737352Y145885D03*
X737702Y128565D03*
X717322Y182676D03*
X720437Y185829D03*
X720472Y179527D03*
Y192125D03*
X704724D03*
X688976Y113385D03*
X670116Y132283D03*
X644100Y111811D03*
X648031Y163779D03*
X654330D03*
X651181Y166929D03*
X640775Y156218D03*
X679526Y144880D03*
X682677Y148031D03*
X688976D03*
X695275D03*
X682677Y154330D03*
X688976D03*
X695275D03*
Y160629D03*
X688976D03*
X682677Y160630D03*
X679527Y163779D03*
X695275Y166929D03*
X688976D03*
X682677D03*
X695275Y173228D03*
X688976D03*
X682677D03*
X679452Y209815D03*
X676379Y192126D03*
X670080Y182678D03*
X660630Y198425D03*
X683913Y213313D03*
X674023Y213815D03*
X674172Y210095D03*
X679400Y213300D03*
X701574Y148031D03*
X707873D03*
X701574Y154330D03*
X707873D03*
Y160629D03*
X701574D03*
X707873Y166929D03*
X701574D03*
Y173228D03*
G54D23*
X177850Y324800D03*
X653200Y408800D03*
X675136Y268500D03*
G54D24*
X245800Y279200D03*
X207600Y292400D03*
X594050Y301755D03*
X608500Y315000D03*
X603650Y315500D03*
X594292Y362291D03*
X590350Y323011D03*
X602649Y349033D03*
X598152Y370130D03*
X598023Y383081D03*
X589394Y384572D03*
X589391Y378202D03*
X752853Y100900D03*
X758050Y164050D03*
X746750Y157700D03*
X750550Y135200D03*
X782500Y134283D03*
X785000Y158900D03*
X760600Y173700D03*
X768700Y129800D03*
X768900Y134800D03*
X786400Y179000D03*
X779200Y178650D03*
X632900Y344950D03*
X634000Y306300D03*
X631800Y316137D03*
X625000Y361700D03*
X627020Y393364D03*
X629770Y369320D03*
X642900Y395400D03*
X645970Y399130D03*
X695625Y282250D03*
X674841Y262854D03*
X660400Y271900D03*
X668600Y242800D03*
%LPD*%
G75*
G54D10*
X15364Y5500D03*
X10364D03*
X5500Y10384D03*
Y15384D03*
Y20384D03*
Y25384D03*
Y30384D03*
Y35384D03*
Y40384D03*
Y45384D03*
Y50384D03*
Y55384D03*
Y60384D03*
Y65384D03*
Y70384D03*
Y75384D03*
Y80384D03*
Y85384D03*
Y90384D03*
Y95384D03*
Y100384D03*
Y105384D03*
Y110384D03*
Y115384D03*
Y120384D03*
Y125384D03*
Y130384D03*
Y135384D03*
Y140384D03*
Y145384D03*
Y150384D03*
Y155384D03*
Y160384D03*
Y165384D03*
Y170384D03*
Y175384D03*
Y180384D03*
Y185384D03*
Y190384D03*
Y195384D03*
Y200384D03*
Y205384D03*
Y210384D03*
Y215384D03*
Y220384D03*
Y225384D03*
Y230384D03*
Y235384D03*
Y240384D03*
Y245384D03*
Y250384D03*
Y255384D03*
Y260384D03*
Y265384D03*
Y270384D03*
Y275384D03*
Y280384D03*
Y285384D03*
Y290384D03*
Y295384D03*
Y300384D03*
Y305384D03*
Y310384D03*
Y315384D03*
Y320384D03*
Y325384D03*
Y330384D03*
Y335384D03*
Y340384D03*
Y345384D03*
Y350384D03*
Y355384D03*
Y360384D03*
Y365384D03*
Y370384D03*
Y375384D03*
Y380384D03*
Y385384D03*
Y390384D03*
Y395384D03*
Y400384D03*
Y405384D03*
Y410384D03*
Y415384D03*
Y420384D03*
Y425384D03*
Y430384D03*
Y435384D03*
Y440384D03*
Y445384D03*
Y450384D03*
Y455384D03*
Y460384D03*
Y465384D03*
Y470384D03*
Y475384D03*
Y480384D03*
Y485384D03*
Y530384D03*
Y525384D03*
Y520384D03*
Y515384D03*
Y510384D03*
Y505384D03*
Y490384D03*
Y495384D03*
Y500384D03*
Y535384D03*
Y540384D03*
Y545384D03*
Y550384D03*
Y555384D03*
Y560384D03*
X10266Y565366D03*
X15266D03*
X75364Y5500D03*
X70364D03*
X65364D03*
X60364D03*
X55364D03*
X50364D03*
X45364D03*
X40364D03*
X35364D03*
X30364D03*
X25364D03*
X20364D03*
X20266Y565366D03*
X25266D03*
X30266D03*
X35266D03*
X40266D03*
X45266D03*
X50266D03*
X55266D03*
X60266D03*
X65266D03*
X70266D03*
X75266D03*
X95364Y5500D03*
X90364D03*
X85364D03*
X80364D03*
X80266Y565366D03*
X85266D03*
X90266D03*
X95266D03*
X100266D03*
X105266D03*
X110266D03*
X115266D03*
X120266D03*
X125266D03*
X130266D03*
X135266D03*
X200364Y5500D03*
X195364D03*
X190364D03*
X185364D03*
X180364D03*
X175364D03*
X170364D03*
X198557Y153196D03*
X174995Y353588D03*
Y358388D03*
X165195D03*
X169995D03*
Y353588D03*
X158067Y378857D03*
X200266Y565366D03*
X195266D03*
X190266D03*
X185266D03*
X180266D03*
X175266D03*
X140266D03*
X145266D03*
X150266D03*
X155266D03*
X160266D03*
X165266D03*
X170266D03*
X260364Y5500D03*
X255364D03*
X250364D03*
X245364D03*
X240364D03*
X235364D03*
X230364D03*
X225364D03*
X220364D03*
X215364D03*
X210364D03*
X205364D03*
X205266Y565366D03*
X210266D03*
X215266D03*
X220266D03*
X225266D03*
X230266D03*
X235266D03*
X240266D03*
X245266D03*
X250266D03*
X255266D03*
X260266D03*
X325364Y5500D03*
X320364D03*
X315364D03*
X310364D03*
X305364D03*
X300364D03*
X295364D03*
X290364D03*
X285364D03*
X280364D03*
X275364D03*
X270364D03*
X265364D03*
X265266Y565366D03*
X270266D03*
X275266D03*
X280266D03*
X285266D03*
X290266D03*
X295266D03*
X300266D03*
X305266D03*
X310266D03*
X315266D03*
X320266D03*
X325266D03*
X330364Y5500D03*
X350586Y495815D03*
X355523Y495025D03*
X360461Y494236D03*
X365398Y493446D03*
X370335Y492656D03*
X375272Y491866D03*
X380210Y491077D03*
X385169Y490563D03*
X329156Y545492D03*
Y540492D03*
Y535492D03*
Y530492D03*
Y525492D03*
Y520492D03*
Y515492D03*
Y560492D03*
Y555492D03*
Y550492D03*
X405169Y490563D03*
X410169D03*
X415169D03*
X420169D03*
X425169D03*
X430169D03*
X435169D03*
X440169D03*
X445146Y490850D03*
X450083Y491640D03*
X390169Y490563D03*
X395169D03*
X400169D03*
X469832Y494799D03*
X474769Y495589D03*
X455020Y492430D03*
X459958Y493219D03*
X464895Y494009D03*
X497636Y515532D03*
Y520532D03*
Y525532D03*
Y530532D03*
Y535532D03*
Y540532D03*
Y545532D03*
Y550532D03*
Y555532D03*
Y560532D03*
X502550Y565366D03*
X507550D03*
X512550D03*
X570234Y298026D03*
X572634Y293526D03*
X572062Y384378D03*
X517550Y565366D03*
X522550D03*
X527550D03*
X532550D03*
X537550D03*
X542550D03*
X547550D03*
X552550D03*
X557550D03*
X562550D03*
X567550D03*
X572550D03*
X591446Y6545D03*
X596446D03*
X601446D03*
X606446D03*
X611446D03*
X616446D03*
X621446D03*
X636446D03*
X631446D03*
X626446D03*
X575134Y298026D03*
X577534Y293526D03*
X580034Y298026D03*
X576862Y384378D03*
X581087Y379569D03*
X576287D03*
X581692Y384378D03*
X635000Y427784D03*
X577550Y565366D03*
X582550D03*
X587550D03*
X592550D03*
X597550D03*
X602550D03*
X607550D03*
X612550D03*
X617550D03*
X622550D03*
X627550D03*
X632550D03*
X641446Y6545D03*
X646446D03*
X651446D03*
X696446D03*
X691446D03*
X661446D03*
X656446D03*
X686446D03*
X681446D03*
X676446D03*
X671446D03*
X666446D03*
X655964Y52248D03*
X637705Y298765D03*
X642705D03*
X696900Y337800D03*
X697500Y358200D03*
X637705Y303765D03*
X642705D03*
X655532Y425245D03*
X658032Y420245D03*
X653032D03*
X659000Y428900D03*
X652200Y429100D03*
X637550Y565366D03*
X642550D03*
X647550D03*
X652550D03*
X657550D03*
X662550D03*
X667550D03*
X672550D03*
X677550D03*
X682550D03*
X687550D03*
X692550D03*
X697550D03*
X701446Y6545D03*
X714600Y338900D03*
Y348500D03*
Y343700D03*
X709800Y348500D03*
Y343700D03*
X706500Y337800D03*
X701700D03*
X707100Y358200D03*
X702300D03*
X722100Y368300D03*
X717300D03*
X712500D03*
X742200Y380400D03*
Y370800D03*
Y375600D03*
X728700Y381000D03*
Y376200D03*
Y371400D03*
X722100Y363500D03*
X717300D03*
X712500D03*
X702550Y565366D03*
X707550D03*
X712550D03*
X717550D03*
X722550D03*
X727550D03*
X732550D03*
X737550D03*
X742550D03*
X747550D03*
X752550D03*
X757550D03*
X821272Y49340D03*
Y44340D03*
Y39340D03*
Y34340D03*
Y29340D03*
Y24340D03*
Y19340D03*
Y14340D03*
Y9340D03*
X815364Y5500D03*
X810364D03*
X805364D03*
X800364D03*
X795364D03*
X790364D03*
X785364D03*
X780364D03*
X775364D03*
X770364D03*
X765364D03*
X821272Y114340D03*
Y109340D03*
Y104340D03*
Y99340D03*
Y94340D03*
Y89340D03*
Y84340D03*
Y79340D03*
Y74340D03*
Y69340D03*
Y64340D03*
Y59340D03*
Y54340D03*
Y174340D03*
Y169340D03*
Y164340D03*
Y159340D03*
Y154340D03*
Y149340D03*
Y144340D03*
Y139340D03*
Y134340D03*
Y129340D03*
Y124340D03*
Y119340D03*
Y234340D03*
Y229340D03*
Y224340D03*
Y219340D03*
Y214340D03*
Y209340D03*
Y204340D03*
Y199340D03*
Y194340D03*
Y189340D03*
Y184340D03*
Y179340D03*
Y299340D03*
Y294340D03*
Y289340D03*
Y284340D03*
Y279340D03*
Y274340D03*
Y269340D03*
Y264340D03*
Y259340D03*
Y254340D03*
Y249340D03*
Y244340D03*
Y239340D03*
Y359340D03*
Y354340D03*
Y349340D03*
Y344340D03*
Y339340D03*
Y334340D03*
Y329340D03*
Y324340D03*
Y319340D03*
Y314340D03*
Y309340D03*
Y304340D03*
Y424340D03*
Y419340D03*
Y414340D03*
Y409340D03*
Y404340D03*
Y399340D03*
Y394340D03*
Y389340D03*
Y384340D03*
Y379340D03*
Y374340D03*
Y369340D03*
Y364340D03*
Y484340D03*
Y479340D03*
Y474340D03*
Y469340D03*
Y464340D03*
Y459340D03*
Y454340D03*
Y449340D03*
Y444340D03*
Y439340D03*
Y434340D03*
Y429340D03*
Y504340D03*
Y509340D03*
Y514340D03*
Y519340D03*
Y524340D03*
Y529340D03*
Y549340D03*
Y544340D03*
Y539340D03*
Y534340D03*
Y499340D03*
Y494340D03*
Y489340D03*
X762550Y565366D03*
X767550D03*
X772550D03*
X777550D03*
X782550D03*
X787550D03*
X792550D03*
X797550D03*
X802550D03*
X807550D03*
X812550D03*
X817550D03*
X821272Y559340D03*
Y554340D03*
G54D20*
G01X45650Y250280D02*
X47750Y248180D01*
X80366D01*
X101034Y227512D01*
Y157808D01*
X123500Y135342D01*
Y103571D01*
X133919Y93152D01*
X179833D01*
X226067Y46918D01*
X306508D01*
X306509Y46917D01*
X308165D01*
X357911Y96663D01*
Y131022D01*
X361758Y134869D01*
Y161021D01*
X369815Y169078D01*
X371316D01*
X374616Y172378D01*
G01X80688Y281695D02*
Y279815D01*
X69473Y268600D01*
X58003D01*
X45650Y256247D01*
Y250280D01*
G01X370061Y172433D02*
X369828D01*
X359723Y162328D01*
Y138670D01*
X355911Y134858D01*
Y97492D01*
X307337Y48918D01*
X226896D01*
X180087Y95727D01*
X134173D01*
X125500Y104400D01*
Y136171D01*
X103034Y158637D01*
Y230022D01*
X82776Y250280D01*
X49320D01*
G01D02*
Y255917D01*
X57303Y263900D01*
X67893D01*
X80688Y276695D01*
G01X250137Y36053D02*
X229496D01*
X176897Y88652D01*
X132055D01*
X118650Y102057D01*
Y133828D01*
X96448Y156030D01*
Y224119D01*
X77036Y243531D01*
X39218D01*
X32469Y250280D01*
G01X510700Y367309D02*
Y369981D01*
X497499Y383182D01*
X495102D01*
X488237Y390047D01*
X406696D01*
X373893Y422850D01*
X310396D01*
X250079Y483167D01*
X157774D01*
X76300Y401693D01*
Y379001D01*
X59600Y362301D01*
Y334880D01*
X58900Y334180D01*
G01X506700Y367309D02*
Y371152D01*
X497067Y380785D01*
X494670D01*
X487408Y388047D01*
X405867D01*
X375914Y418000D01*
X310936D01*
X247769Y481167D01*
X159196D01*
X78515Y400486D01*
Y378317D01*
X62325Y362127D01*
Y334068D01*
G01X80700Y309400D02*
X81144Y309844D01*
Y311527D01*
X80071Y312600D01*
X53900D01*
X33453Y333047D01*
Y356982D01*
X37000Y360529D01*
Y362200D01*
X35800Y363400D01*
G01X37900Y334380D02*
X39000Y335480D01*
Y348429D01*
X47635Y357064D01*
Y372435D01*
X59600Y384400D01*
Y403592D01*
X143175Y487167D01*
X256158D01*
X316475Y426850D01*
X375551D01*
X408354Y394047D01*
X477850D01*
X477851Y394048D01*
X491052D01*
X495750Y389350D01*
X507550D01*
X510019Y386881D01*
X534304D01*
X538357Y384249D01*
X538359Y384248D01*
X539278Y383650D01*
X546617Y376311D01*
X546618Y376309D01*
X546631Y376290D01*
X547603Y374794D01*
Y373404D01*
X550100Y370907D01*
Y348300D01*
G01X80600Y304600D02*
X83144Y307144D01*
Y312356D01*
X80900Y314600D01*
X54851D01*
X35453Y333998D01*
Y356153D01*
X39000Y359700D01*
Y362300D01*
X40100Y363400D01*
G01X41325Y334268D02*
Y347925D01*
X49635Y356235D01*
Y371606D01*
X61600Y383571D01*
Y402203D01*
X144564Y485167D01*
X253149D01*
X313466Y424850D01*
X374722D01*
X407525Y392047D01*
X478679D01*
X478680Y392048D01*
X488626D01*
X488627Y392047D01*
X489066D01*
X493763Y387350D01*
X506721D01*
X509190Y384881D01*
X533709D01*
X537194Y382618D01*
X537195D01*
X538012Y382087D01*
X544630Y375469D01*
Y355189D01*
X546100Y353719D01*
Y348300D01*
G01X164020Y101127D02*
X135673D01*
X130850Y105950D01*
Y137350D01*
X107742Y160458D01*
Y326275D01*
X102667Y331350D01*
X102333D01*
X99950Y333733D01*
Y358650D01*
X96445Y362155D01*
Y403745D01*
X104900Y412200D01*
G01X233759Y64752D02*
Y68741D01*
X204773Y97727D01*
X135373D01*
X127500Y105600D01*
Y137000D01*
X105742Y158758D01*
Y230475D01*
X93884Y242333D01*
G01X80688Y281695D02*
X78400Y283983D01*
Y307100D01*
X80700Y309400D01*
G01X80688Y276695D02*
X83000Y279007D01*
Y298600D01*
X80600Y301000D01*
Y304600D01*
G01Y334580D02*
X81050Y335030D01*
Y340557D01*
X84021Y343528D01*
Y373896D01*
X81795Y376122D01*
Y395034D01*
X147661Y460900D01*
X262587D01*
X307811Y415676D01*
X375175D01*
X404804Y386047D01*
X485757D01*
X498304Y373500D01*
X501523D01*
X504700Y370323D01*
Y366500D01*
X505992Y365208D01*
X506818D01*
X506967Y365059D01*
X510967D01*
X521336Y354690D01*
X539468D01*
X544100Y350058D01*
Y347683D01*
X545483Y346300D01*
X546655D01*
X550056Y342899D01*
Y338039D01*
X554685Y333410D01*
G01X547927Y342199D02*
X545826Y344300D01*
X544654D01*
X542100Y346854D01*
Y349229D01*
X538733Y352596D01*
X517604D01*
X508900Y361300D01*
X505492D01*
X504200Y362592D01*
Y364100D01*
X500350Y367950D01*
Y368625D01*
X484928Y384047D01*
X403975D01*
X375011Y413011D01*
X305825D01*
X259936Y458900D01*
X148490D01*
X83795Y394205D01*
Y376951D01*
X86021Y374725D01*
Y342699D01*
X84025Y340703D01*
Y334468D01*
G01X543646Y342347D02*
X542275D01*
X538362Y346260D01*
X532292D01*
X528532Y342500D01*
X501521D01*
X476050Y367971D01*
Y368267D01*
X474967Y369350D01*
X471059D01*
X466362Y374047D01*
X399830D01*
X389577Y384300D01*
X311709D01*
X302095Y374686D01*
X291419D01*
X259897Y343164D01*
X253621D01*
X234657Y324200D01*
X207772D01*
X204749Y327223D01*
Y371531D01*
X183023Y393257D01*
X138588D01*
X102400Y357069D01*
Y333900D01*
G01X106500D02*
Y355899D01*
X139447Y388846D01*
X181559D01*
X201454Y368951D01*
Y326336D01*
X205590Y322200D01*
X235486D01*
X253944Y340658D01*
X260514D01*
X292018Y372162D01*
X302400D01*
X312298Y382060D01*
X388988D01*
X399001Y372047D01*
X462215D01*
X467025Y367237D01*
X470433D01*
X472268Y365402D01*
X474790D01*
X499692Y340500D01*
X529361D01*
X533121Y344260D01*
X537533D01*
X539446Y342347D01*
G01X212198Y328316D02*
Y375075D01*
X185164Y402109D01*
X127333D01*
X108624Y383400D01*
X106709D01*
G01X208648Y328452D02*
Y373697D01*
X184486Y397859D01*
X126869D01*
X112023Y383013D01*
G01X360000Y410000D02*
X304234D01*
X257334Y456900D01*
X149529D01*
X104900Y412271D01*
Y412200D01*
G01X107582Y391266D02*
Y412124D01*
X150358Y454900D01*
X254300D01*
X259800Y449400D01*
Y423400D01*
G01X250137Y36053D02*
X320239D01*
X327158Y29134D01*
X338583D01*
G01X342000Y141600D02*
X341600Y141200D01*
Y118113D01*
X311087Y87600D01*
X286283D01*
X271283Y72600D01*
X255300D01*
G01X255154Y69177D02*
X279377D01*
X295751Y85551D01*
X311867D01*
X343911Y117595D01*
Y144218D01*
X347879Y148186D01*
Y162970D01*
X365773Y180864D01*
X371019D01*
X372517Y182362D01*
G01X538476Y334365D02*
X536577Y332466D01*
X529265D01*
X522241Y325442D01*
X516458D01*
X511400Y330500D01*
X490770D01*
X481879Y339391D01*
X479226D01*
X469207Y349410D01*
X456904D01*
X446390Y359924D01*
X394150D01*
X386280Y367794D01*
X325277D01*
X298100Y340617D01*
Y322929D01*
X297348Y322177D01*
Y313693D01*
X293019Y309364D01*
X266631D01*
X262097Y313898D01*
Y323619D01*
X261365Y324351D01*
G01X538436Y330918D02*
X539828Y332310D01*
Y332444D01*
X541933Y334549D01*
Y339529D01*
X541129Y340333D01*
X538892D01*
X535059Y336500D01*
X498034D01*
X475184Y359350D01*
X466000D01*
X457303Y368047D01*
X397343D01*
X387330Y378060D01*
X317172D01*
X306448Y367336D01*
X292850D01*
X259027Y333513D01*
X253156D01*
X245943Y326300D01*
G01X246100Y329700D02*
X253763Y337363D01*
X260048D01*
X292847Y370162D01*
X303229D01*
X313127Y380060D01*
X388159D01*
X398172Y370047D01*
X459652D01*
X464780Y364919D01*
X469540D01*
X471259Y363200D01*
X474163D01*
X498863Y338500D01*
X530190D01*
X534100Y342410D01*
G01X230400Y326200D02*
X233828D01*
X254343Y346715D01*
X260619D01*
X305302Y391398D01*
X385308D01*
X400659Y376047D01*
X472478D01*
X478644Y369880D01*
X479624Y368900D01*
X485900D01*
X486950Y367850D01*
Y361269D01*
X497869Y350350D01*
X498905D01*
X499988Y349267D01*
Y348033D01*
X503521Y344500D01*
X527703D01*
X531503Y348300D01*
X536200D01*
G01X230400Y329600D02*
X234399D01*
X254029Y349230D01*
X260305D01*
X304473Y393398D01*
X386137D01*
X401488Y378047D01*
X475797D01*
X482872Y370972D01*
X486828D01*
X488600Y369200D01*
X490226D01*
X492450Y366976D01*
Y362576D01*
X495050Y359976D01*
Y358205D01*
X503988Y349267D01*
Y348157D01*
X505645Y346500D01*
X526874D01*
X530674Y350300D01*
X538200D01*
X540200Y348300D01*
G01X506262Y348500D02*
X506368Y348606D01*
Y349716D01*
X500550Y355534D01*
Y359976D01*
X499467Y361059D01*
X498233D01*
X497000Y362292D01*
Y364697D01*
X496200Y365497D01*
Y367117D01*
X483270Y380047D01*
X402317D01*
X386879Y395485D01*
X303731D01*
X261630Y353384D01*
X231702D01*
X220400Y342082D01*
Y328600D01*
X218400Y326600D01*
G01X218300Y330000D02*
Y342811D01*
X230873Y355384D01*
X260801D01*
X302902Y397485D01*
X387708D01*
X403146Y382047D01*
X484099D01*
X498350Y367796D01*
Y367121D01*
X502200Y363271D01*
Y361763D01*
X502550Y361413D01*
Y356363D01*
X509995Y348918D01*
Y348643D01*
X510138Y348500D01*
G01X259800Y423400D02*
Y412659D01*
X266500Y405959D01*
Y364000D01*
G01X376306Y182715D02*
Y181113D01*
X371770Y176577D01*
X367144D01*
X353880Y163313D01*
Y146880D01*
X347911Y140911D01*
Y115937D01*
X313766Y81792D01*
Y61276D01*
X311182Y58692D01*
G01X276700Y66700D02*
X288000D01*
X298009Y56691D01*
X312091D01*
X315900Y60500D01*
Y77800D01*
X351911Y113811D01*
Y136763D01*
X355500Y140352D01*
Y144500D01*
G01X283385Y100227D02*
Y108983D01*
X302555Y128153D01*
Y245463D01*
X308293Y251201D01*
Y253653D01*
X308292Y253654D01*
Y255473D01*
X308250Y255515D01*
Y262587D01*
X322370Y276707D01*
Y303116D01*
X330032Y310778D01*
Y315000D01*
X331214Y316182D01*
Y318214D01*
X342350Y329350D01*
X380829D01*
X382949Y331470D01*
X416562D01*
X421260Y326772D01*
G01X287385Y100227D02*
Y110154D01*
X304555Y127324D01*
Y244634D01*
X310293Y250372D01*
Y252824D01*
X310294Y252825D01*
Y254481D01*
X310292Y254483D01*
Y256302D01*
X310250Y256344D01*
Y261758D01*
X325729Y277237D01*
Y303646D01*
X332032Y309949D01*
Y314171D01*
X333214Y315353D01*
Y317385D01*
X343179Y327350D01*
X380977D01*
X384097Y330470D01*
X415818D01*
X418883Y327405D01*
Y326850D01*
X421259Y324474D01*
Y322835D01*
G01X291385Y100227D02*
X294015Y102857D01*
X297632D01*
X303334Y108559D01*
Y111939D01*
X308579Y117184D01*
Y122008D01*
X310780Y124209D01*
Y156351D01*
X314301Y159872D01*
Y237430D01*
X321731Y244860D01*
Y263981D01*
X331236Y273486D01*
X341703D01*
X351000Y282783D01*
Y314217D01*
X354683Y317900D01*
X381988D01*
X388473Y324385D01*
X410815D01*
X414404Y320796D01*
X418176D01*
X420074Y318898D01*
X421260D01*
G01X295385Y100227D02*
X309324D01*
X316772Y107675D01*
Y118885D01*
X318780Y120893D01*
Y153035D01*
X322301Y156556D01*
Y233452D01*
X338100Y249251D01*
Y255856D01*
X363879Y281635D01*
X427303D01*
X433070Y287402D01*
G01X306196Y110209D02*
X309929D01*
X312772Y113052D01*
Y120543D01*
X314780Y122551D01*
Y154693D01*
X318301Y158214D01*
Y235110D01*
X331300Y248109D01*
Y263019D01*
X336780Y268499D01*
X342374D01*
X359500Y285625D01*
Y290466D01*
X377534Y308500D01*
X385000D01*
X389313Y312813D01*
X419112D01*
X421260Y314961D01*
G01X314772Y108292D02*
Y119714D01*
X316780Y121722D01*
Y153864D01*
X320301Y157385D01*
Y234281D01*
X335800Y249780D01*
Y259317D01*
X338733Y262250D01*
X338954D01*
X361500Y284796D01*
Y289637D01*
X377863Y306000D01*
X384000D01*
X386637Y308637D01*
X419711D01*
X421260Y307088D01*
G01X311182Y62800D02*
Y82037D01*
X345911Y116766D01*
Y142411D01*
X351880Y148380D01*
Y164142D01*
X366344Y178606D01*
X370970D01*
X371124Y178760D01*
G01X405921Y347159D02*
X405156Y347924D01*
X390391D01*
X383080Y355235D01*
X336812D01*
X312500Y330923D01*
Y319105D01*
X307348Y313953D01*
Y309203D01*
X305709Y307564D01*
Y300550D01*
X307730Y298529D01*
Y286055D01*
X279950Y258275D01*
Y121074D01*
X272937Y114061D01*
Y90362D01*
G01X476200Y334900D02*
X466449Y344651D01*
X457971D01*
X446420Y356202D01*
X393773D01*
X387136Y362839D01*
X325666D01*
X303865Y341038D01*
Y325865D01*
X299348Y321348D01*
Y309690D01*
X294817Y305159D01*
Y285076D01*
X270409Y260668D01*
Y120020D01*
X266895Y116506D01*
Y100227D01*
G01X464567Y311025D02*
Y313217D01*
X461100Y316684D01*
X460651D01*
X458243Y319092D01*
Y319541D01*
X445934Y331850D01*
X433951D01*
X432201Y333600D01*
X428500D01*
X419050Y343050D01*
X405022D01*
X402148Y345924D01*
X389096D01*
X382573Y352447D01*
X337830D01*
X331850Y346467D01*
Y344433D01*
X322023Y334606D01*
Y330198D01*
X316500Y324675D01*
Y320276D01*
X310030Y313806D01*
Y285526D01*
X281950Y257446D01*
Y120245D01*
X274937Y113232D01*
Y95806D01*
X278418Y92325D01*
X283393D01*
G01X464567Y318898D02*
Y322289D01*
X454250Y332606D01*
Y333384D01*
X452537Y335097D01*
X438755D01*
X431002Y342850D01*
X426574D01*
X419500Y349924D01*
X392827D01*
X384728Y358023D01*
X336771D01*
X310500Y331752D01*
Y319934D01*
X305348Y314782D01*
Y310032D01*
X303709Y308393D01*
Y299721D01*
X305730Y297700D01*
Y286884D01*
X277950Y259104D01*
Y121903D01*
X270937Y114890D01*
Y87862D01*
X272937Y85862D01*
G01X413386Y251969D02*
X411149Y254206D01*
Y260336D01*
X408092Y263393D01*
X385793D01*
X377401Y255001D01*
X361231D01*
X330342Y224112D01*
Y153281D01*
X327250Y150189D01*
Y131520D01*
X325343Y129613D01*
Y120685D01*
X321582Y116924D01*
Y112445D01*
X318773Y109636D01*
Y108083D01*
G01X278039Y82185D02*
X273206D01*
X268937Y86454D01*
Y115719D01*
X275950Y122732D01*
Y261326D01*
X297151Y282527D01*
Y304664D01*
X303348Y310861D01*
Y315611D01*
X308200Y320463D01*
Y332281D01*
X314200Y338281D01*
Y344436D01*
X321614Y351850D01*
X323850D01*
X332051Y360051D01*
X386249D01*
X394376Y351924D01*
X425618D01*
X430464Y347078D01*
G01X292385Y108227D02*
X300949Y116791D01*
X305357D01*
X306579Y118013D01*
Y122837D01*
X308555Y124813D01*
Y156955D01*
X312300Y160700D01*
Y240081D01*
X317707Y245488D01*
Y263557D01*
X337732Y283582D01*
Y315036D01*
X342596Y319900D01*
X381780D01*
X388360Y326480D01*
X390210D01*
X390550Y326820D01*
G01X280298Y95556D02*
X276961Y98893D01*
Y111946D01*
X285893Y120878D01*
X292451D01*
X299623Y128050D01*
Y272290D01*
X312030Y284697D01*
Y312977D01*
X318567Y319514D01*
Y323913D01*
X324023Y329369D01*
Y332340D01*
X339606Y347923D01*
X346467D01*
X348818Y350274D01*
X380893D01*
X387243Y343924D01*
X401177D01*
X405783Y339318D01*
G01X417323Y251969D02*
X415124Y254168D01*
Y260298D01*
X411029Y264393D01*
X381829D01*
X380829Y263393D01*
X365643D01*
X328342Y226092D01*
Y154110D01*
X325250Y151018D01*
Y132349D01*
X323343Y130442D01*
Y121514D01*
X319533Y117704D01*
Y114283D01*
G01X324026Y115936D02*
Y116539D01*
X327343Y119856D01*
Y128784D01*
X329250Y130691D01*
Y149360D01*
X332763Y152873D01*
Y196120D01*
X346568Y209925D01*
Y233791D01*
X365477Y252700D01*
X378571D01*
X388264Y262393D01*
X405155D01*
X407830Y259718D01*
Y253588D01*
X413386Y248032D01*
G01X421260Y251969D02*
X418873Y254356D01*
Y260486D01*
X413966Y265393D01*
X369185D01*
X369184Y265394D01*
X364815D01*
X326342Y226921D01*
Y154939D01*
X323250Y151847D01*
Y133178D01*
X321343Y131271D01*
Y122343D01*
G01X321051Y134028D02*
Y152477D01*
X324301Y155727D01*
Y231090D01*
X362478Y269267D01*
X414029D01*
X414936Y268360D01*
Y267911D01*
X421454Y261393D01*
X421903D01*
X422810Y260486D01*
Y251326D01*
X421284Y249800D01*
X419091D01*
X417323Y248032D01*
G01X417322Y322835D02*
X415130D01*
X411772Y326193D01*
Y326642D01*
X409944Y328470D01*
X386722D01*
X380152Y321900D01*
X341767D01*
X335214Y315347D01*
Y314524D01*
X334032Y313342D01*
Y282711D01*
X312250Y260929D01*
Y257173D01*
X312292Y257131D01*
Y255312D01*
X312294Y255310D01*
Y251996D01*
X312293Y251995D01*
Y249543D01*
X306555Y243805D01*
Y126495D01*
X304579Y124519D01*
Y118842D01*
X304529Y118792D01*
G01X413386Y314962D02*
X411321Y317027D01*
X389527D01*
X384450Y311950D01*
X378155D01*
X357500Y291295D01*
Y286454D01*
X341546Y270500D01*
X331079D01*
X325650Y265071D01*
Y245288D01*
X316301Y235939D01*
Y159043D01*
X312780Y155522D01*
Y123380D01*
X310711Y121311D01*
Y113820D01*
G01X306292Y252825D02*
X304262Y254855D01*
Y268771D01*
X317455Y281964D01*
Y298035D01*
X320149Y300729D01*
Y309474D01*
X325514Y314839D01*
Y318545D01*
X341369Y334400D01*
X361250D01*
X364050Y337200D01*
G01X302262Y262642D02*
X302184Y262720D01*
Y269522D01*
X315455Y282793D01*
Y298864D01*
X316150Y299559D01*
Y314268D01*
X323650Y321768D01*
Y326167D01*
X324733Y327250D01*
X327867D01*
X343467Y342850D01*
X369500D01*
X374250Y347600D01*
G01X265365Y324351D02*
X264097Y323083D01*
Y314727D01*
X267157Y311667D01*
X292112D01*
X295348Y314903D01*
Y323481D01*
X296100Y324233D01*
Y342083D01*
X323811Y369794D01*
X387109D01*
X394856Y362047D01*
X448387D01*
X459024Y351410D01*
X470036D01*
X479077Y342369D01*
X483277D01*
X493291Y332358D01*
X511942D01*
X517208Y327092D01*
X519263D01*
G01X288536Y314764D02*
X286892Y316408D01*
Y341898D01*
X319054Y374060D01*
X385672D01*
X395685Y364047D01*
X450380D01*
X461017Y353410D01*
X475466D01*
X479509Y349367D01*
Y346894D01*
X481816Y344587D01*
X484111D01*
X495202Y333499D01*
X513263D01*
X517081Y329681D01*
X518862D01*
X519629Y330448D01*
G01X521914Y332907D02*
X521691Y333130D01*
X516005D01*
X514335Y334800D01*
X496905D01*
X476295Y355410D01*
X463073D01*
X452436Y366047D01*
X396514D01*
X386501Y376060D01*
X318225D01*
X284892Y342727D01*
Y323536D01*
X275696Y314340D01*
G01X401575Y248032D02*
X400152Y249455D01*
X388055D01*
X352570Y213970D01*
Y204544D01*
X339879Y191853D01*
Y151502D01*
X335535Y147158D01*
Y128489D01*
X333649Y126603D01*
Y112991D01*
X328711Y108053D01*
G01X335722Y94574D02*
X353911Y112763D01*
Y135934D01*
X357723Y139746D01*
Y164327D01*
X367973Y174577D01*
X373050D01*
X374915Y176442D01*
G01X349911Y136954D02*
Y114763D01*
X329722Y94574D01*
G01X328600Y114400D02*
X329343Y115143D01*
Y127955D01*
X331250Y129862D01*
Y148531D01*
X334791Y152072D01*
Y193126D01*
X348568Y206903D01*
Y232962D01*
X365506Y249900D01*
X378600D01*
X386650Y257950D01*
X402270D01*
X403620Y256600D01*
Y255402D01*
X405512Y253510D01*
Y248032D01*
G01X331649Y126111D02*
Y127432D01*
X333250Y129033D01*
Y147702D01*
X336946Y151398D01*
Y191749D01*
X350570Y205373D01*
Y215035D01*
X380751Y245216D01*
Y248751D01*
X386150Y254150D01*
X401138D01*
X403944Y251344D01*
Y245663D01*
X405512Y244095D01*
G01X401575D02*
X400025Y245645D01*
X389903D01*
X356570Y212312D01*
Y202886D01*
X343879Y190195D01*
Y149844D01*
X339535Y145500D01*
Y124724D01*
X339049Y124238D01*
G01X413386Y244095D02*
X411836Y242545D01*
X404869D01*
X403962Y243452D01*
Y243901D01*
X401381Y246482D01*
X400932D01*
X400214Y247200D01*
X388629D01*
X354570Y213141D01*
Y203715D01*
X341879Y191024D01*
Y150673D01*
X337535Y146329D01*
Y127660D01*
X335994Y126119D01*
G01X401575Y240158D02*
X400025Y241708D01*
X388795D01*
X358570Y211483D01*
Y202057D01*
X345879Y189366D01*
Y149015D01*
X341913Y145049D01*
G01X351723Y178499D02*
Y191427D01*
X360570Y200274D01*
Y210654D01*
X388516Y238600D01*
X403954D01*
X405512Y240158D01*
G01X354143Y183439D02*
X357064Y186360D01*
X366015D01*
X370559Y190904D01*
Y195401D01*
X368570Y197390D01*
Y206370D01*
X375400Y213200D01*
X382294D01*
X382994Y213900D01*
Y219994D01*
X389797Y226797D01*
X406155D01*
X411579Y232221D01*
Y236479D01*
X413387Y238287D01*
Y240158D01*
G01X362260Y184360D02*
X368263D01*
X371390Y187487D01*
X377182D01*
X391938Y202243D01*
Y205310D01*
X393254Y206626D01*
X393858D01*
X395480Y208248D01*
Y208852D01*
X397677Y211049D01*
X414029D01*
X415455Y212475D01*
Y224735D01*
X417076Y226356D01*
X421462D01*
X422810Y227704D01*
Y246482D01*
X421260Y248032D01*
G01X364169Y188366D02*
X362570Y189965D01*
Y209670D01*
X389000Y236100D01*
G01X366460Y191794D02*
X364570Y193684D01*
Y208299D01*
X390942Y234671D01*
X400025D01*
X401575Y236221D01*
G01X368558Y194540D02*
X367049Y196049D01*
Y196082D01*
X366570Y196561D01*
Y207470D01*
X389681Y230581D01*
X402065D01*
X403708Y232224D01*
Y233608D01*
X405512Y235412D01*
Y236221D01*
G01X379415Y194608D02*
X379989D01*
X382156Y196775D01*
Y203247D01*
X389784Y210875D01*
X390388D01*
X392138Y212625D01*
Y213229D01*
X393760Y214851D01*
X410112D01*
X411368Y216107D01*
Y225569D01*
X418873Y233074D01*
Y242545D01*
X417323Y244095D01*
G01X370570Y198219D02*
Y205034D01*
X373036Y207500D01*
X382391D01*
X385300Y210409D01*
Y218800D01*
X389304Y222804D01*
X405503D01*
X412449Y229750D01*
X413308D01*
X417322Y233764D01*
Y236221D01*
G01X425197Y291339D02*
X423718D01*
X421571Y289192D01*
X386200D01*
X384408Y287400D01*
X380400D01*
G01X382000Y296500D02*
X383163Y297663D01*
X430684D01*
X433071Y295276D01*
G01X384600Y285600D02*
X421202D01*
X424753Y289151D01*
X429139D01*
X431327Y291339D01*
X433071D01*
G01X379000Y272600D02*
X380850D01*
X382112Y273862D01*
X430393D01*
X431080Y274549D01*
Y283880D01*
X432700Y285500D01*
X435105D01*
X437007Y287402D01*
G01X429134Y291340D02*
X427860D01*
X426100Y293100D01*
X386300D01*
X384300Y291100D01*
G01X425197Y303150D02*
X422951Y305396D01*
X386061D01*
X385887Y305222D01*
G01X381396Y302610D02*
X382406Y301600D01*
X430684D01*
X433071Y299213D01*
G01X460630Y303150D02*
X458886D01*
X457336Y304700D01*
X456887D01*
X454437Y307150D01*
Y307775D01*
X453219Y308993D01*
X452594D01*
X450369Y311218D01*
Y311667D01*
X449462Y312574D01*
X449013D01*
X446432Y315155D01*
Y315604D01*
X445525Y316511D01*
X445076D01*
X444362Y317225D01*
X432337D01*
X430953Y318609D01*
Y322017D01*
X419420Y333550D01*
X402450D01*
X399500Y336500D01*
Y338500D01*
X398500Y339500D01*
X366350D01*
X364050Y337200D01*
G01X374250Y347600D02*
X379688D01*
X385620Y341668D01*
X400332D01*
X406450Y335550D01*
X420250D01*
X431415Y324385D01*
X445525D01*
X451866Y318044D01*
Y317595D01*
X456244Y313217D01*
X456693D01*
X459080Y310830D01*
Y310381D01*
X460491Y308970D01*
X461300D01*
X462900Y307370D01*
Y306600D01*
X463017Y306483D01*
Y306445D01*
X464567Y304895D01*
Y303151D01*
G01X359200Y315800D02*
X361050Y313950D01*
X379950D01*
X386448Y320448D01*
X411552D01*
X415206Y316794D01*
X421620D01*
X423301Y315113D01*
Y310727D01*
X424655Y309373D01*
X426848D01*
X433071Y303150D01*
G01X647103Y13964D02*
X645092Y11953D01*
X642124D01*
X638961Y15116D01*
X624211D01*
X613782Y25545D01*
Y123202D01*
X604952Y132032D01*
Y157445D01*
X599381Y163016D01*
Y223448D01*
X593989Y228840D01*
Y254517D01*
X557866Y290640D01*
X533147D01*
X522914Y300873D01*
X479200D01*
X475977Y297650D01*
X470400D01*
X466476Y293726D01*
X445775D01*
X442500Y297001D01*
X437027D01*
X435400Y298628D01*
Y306951D01*
X432877Y309474D01*
X432428D01*
X431521Y310381D01*
Y310830D01*
X428940Y313411D01*
X428491D01*
X427584Y314318D01*
Y314767D01*
X425003Y317348D01*
X424554D01*
X423100Y318802D01*
Y319251D01*
X421211Y321140D01*
X420761D01*
X419385Y322516D01*
Y322965D01*
X417128Y325222D01*
X416680D01*
X415773Y326129D01*
Y326578D01*
X412881Y329470D01*
X385558D01*
X379988Y323900D01*
X360300D01*
G01X401700Y337350D02*
X401800D01*
X404600Y334550D01*
X419835D01*
X433806Y320579D01*
X445394D01*
X447269Y318704D01*
Y318255D01*
X448176Y317348D01*
X448625D01*
X455143Y310830D01*
Y310381D01*
X456050Y309474D01*
X456499D01*
X459080Y306893D01*
Y306444D01*
X459987Y305537D01*
X460436D01*
X462300Y303673D01*
Y303225D01*
X463924Y301601D01*
X466954D01*
X468504Y303151D01*
G01X456694Y295276D02*
X450370Y301600D01*
X440302D01*
X439395Y302507D01*
Y306893D01*
X437651Y308637D01*
X437202D01*
X434621Y311218D01*
Y311667D01*
X433714Y312574D01*
X433265D01*
X430684Y315155D01*
Y315604D01*
X428940Y317348D01*
X428491D01*
X427200Y318639D01*
Y323025D01*
X417675Y332550D01*
X397508D01*
X392959Y337099D01*
G01X405921Y347159D02*
X408013Y345067D01*
X420933D01*
X425500Y340500D01*
X427500D01*
X434788Y333212D01*
X448509D01*
X462180Y319541D01*
Y319092D01*
X466224Y315048D01*
Y309369D01*
X468505Y307088D01*
G01X430464Y347078D02*
X434692Y342850D01*
X453817D01*
X458583Y338084D01*
Y336910D01*
X460098Y335395D01*
X462282D01*
X470473Y327204D01*
G01X445000Y422000D02*
X446000Y421000D01*
X455469D01*
X485269Y450800D01*
X496900D01*
X500670Y454570D01*
X555210D01*
X562930Y462290D01*
X589740D01*
X598500Y471050D01*
X640570D01*
X668090Y443530D01*
X671290D01*
X677007Y437813D01*
X683250D01*
G01X638103Y13100D02*
X621727D01*
X610895Y23932D01*
Y122160D01*
X601621Y131434D01*
Y156326D01*
X595607Y162340D01*
Y223573D01*
X591989Y227191D01*
Y253688D01*
X557096Y288581D01*
X532208D01*
X522021Y298768D01*
X514095D01*
X512659Y297332D01*
X479150D01*
X474968Y293150D01*
X468700D01*
X466889Y291339D01*
X460630D01*
G01X468500Y347500D02*
Y346158D01*
X478334Y336324D01*
X480324D01*
X487326Y329322D01*
X507517D01*
X519027Y317812D01*
Y311959D01*
X534251Y296735D01*
X557582D01*
X606153Y248164D01*
Y166320D01*
X612173Y160300D01*
Y133619D01*
X620222Y125570D01*
Y26617D01*
X627500Y19339D01*
G01X464567Y307088D02*
X466255Y305400D01*
X475500D01*
X479483Y309383D01*
X517233D01*
X532026Y294590D01*
X556745D01*
X596200Y255135D01*
Y230700D01*
X602788Y224112D01*
Y164494D01*
X608371Y158911D01*
Y133366D01*
X616860Y124877D01*
Y26206D01*
X625924Y17142D01*
X639764D01*
X643103Y13803D01*
G01X680300Y384900D02*
X680452Y385052D01*
Y408618D01*
X689749Y417915D01*
X746127D01*
X755300Y408742D01*
Y327222D01*
X702764Y274686D01*
Y266591D01*
X704708Y264647D01*
G01X790714Y237308D02*
X786941Y233535D01*
Y221370D01*
X768898Y203327D01*
Y193664D01*
X748349Y173115D01*
X741952D01*
G01X739300Y287611D02*
X737260Y285571D01*
X727458D01*
X720421Y278534D01*
Y271117D01*
X712587Y263283D01*
Y244104D01*
X710708Y242225D01*
Y239126D01*
X712587Y237247D01*
Y225714D01*
X725009Y213292D01*
G01X751693Y255540D02*
X756912D01*
X757412Y255040D01*
Y254040D01*
X756912Y253540D01*
X750337D01*
X749837Y253040D01*
Y252040D01*
X750337Y251540D01*
X756059D01*
X756559Y251040D01*
Y250040D01*
X756059Y249540D01*
X750058D01*
X749558Y249040D01*
Y233431D01*
X750058Y232931D01*
X751058D01*
X751558Y233431D01*
Y246477D01*
X752058Y246977D01*
X753058D01*
X753558Y246477D01*
Y232406D01*
X744839Y223687D01*
Y213187D01*
X743645Y211993D01*
Y205647D01*
X741814Y203816D01*
Y197877D01*
X739852Y195915D01*
G01X737832Y202664D02*
X740839Y205671D01*
Y224785D01*
X740339Y225285D01*
X737312D01*
X736812Y225785D01*
Y226860D01*
X737312Y227360D01*
X738511D01*
X739011Y227860D01*
Y228860D01*
X738511Y229360D01*
X737312D01*
X736812Y229860D01*
Y230860D01*
X737312Y231360D01*
X738406D01*
X738906Y231860D01*
Y232860D01*
X738406Y233360D01*
X737312D01*
X736812Y233860D01*
Y234860D01*
X737312Y235360D01*
X740615D01*
X741115Y235860D01*
Y236860D01*
X740615Y237360D01*
X739084D01*
X738584Y237860D01*
Y238860D01*
X739084Y239360D01*
X744804D01*
X745304Y239860D01*
Y240860D01*
X744804Y241360D01*
X739031D01*
X738531Y241860D01*
Y242860D01*
X739031Y243360D01*
X742555D01*
X743055Y243860D01*
Y244860D01*
X742555Y245360D01*
X739135D01*
X738635Y245860D01*
Y246860D01*
X739135Y247360D01*
X742868D01*
X743368Y247860D01*
Y248860D01*
X742868Y249360D01*
X739427D01*
X738927Y249860D01*
Y250860D01*
X739427Y251360D01*
X740888D01*
X741388Y251860D01*
Y272416D01*
X741888Y272916D01*
X743007D01*
X743507Y272416D01*
Y251685D01*
G01X761484Y255581D02*
X764436Y252629D01*
Y238224D01*
X764936Y237724D01*
X765936D01*
X766436Y238224D01*
Y249061D01*
X766936Y249561D01*
X767936D01*
X768436Y249061D01*
Y227428D01*
X754839Y213831D01*
Y209216D01*
X752645Y207022D01*
Y197214D01*
X744332Y188901D01*
X737732D01*
X737656Y188977D01*
X729920D01*
G01X747558Y247274D02*
Y280189D01*
X747058Y280689D01*
X746058D01*
X745558Y280189D01*
Y245556D01*
X747388Y243726D01*
Y229137D01*
X746888Y228637D01*
X745888D01*
X745388Y229137D01*
Y236776D01*
X744888Y237276D01*
X743888D01*
X743388Y236776D01*
Y235080D01*
X741033Y232725D01*
Y227449D01*
X742839Y225643D01*
Y213671D01*
X741839Y212671D01*
Y205256D01*
X739752Y203169D01*
Y199615D01*
G01X761484Y251581D02*
X762436Y250629D01*
Y232235D01*
X762936Y231735D01*
X763936D01*
X764436Y232235D01*
Y234903D01*
X764936Y235403D01*
X765936D01*
X766436Y234903D01*
Y228257D01*
X756525Y218346D01*
X755819D01*
X755111Y219055D01*
Y219761D01*
X763348Y227998D01*
Y228704D01*
X762640Y229413D01*
X761934D01*
X752839Y220318D01*
Y210045D01*
X750645Y207851D01*
Y198043D01*
X743153Y190551D01*
X738416D01*
G01X729920Y182678D02*
X730605Y181993D01*
X740890D01*
X741818Y181065D01*
X747812D01*
X762839Y196092D01*
Y205900D01*
X766569Y209630D01*
Y213721D01*
X769971Y217123D01*
X773803D01*
X780837Y224157D01*
Y240885D01*
G01X745485Y197673D02*
X748645Y200833D01*
Y208680D01*
X750839Y210874D01*
Y221200D01*
X759558Y229919D01*
Y241027D01*
G01Y247274D02*
X757558Y245274D01*
Y230748D01*
X748839Y222029D01*
Y211703D01*
X746645Y209509D01*
Y202833D01*
X745485Y201673D01*
G01X774637Y267746D02*
X772637Y265746D01*
Y262917D01*
X773808Y261746D01*
X775466D01*
X782837Y254375D01*
Y223224D01*
X774140Y214527D01*
X770204D01*
X768833Y213156D01*
Y209065D01*
X764839Y205071D01*
Y195263D01*
X748641Y179065D01*
X741402D01*
X740352Y180115D01*
G01X770637Y267746D02*
X768730Y265839D01*
Y258935D01*
X770637Y257028D01*
Y252857D01*
X776420Y247074D01*
Y225398D01*
X772798Y221776D01*
X768966D01*
X762566Y215376D01*
Y212680D01*
X761936Y212050D01*
X759527D01*
X758839Y211362D01*
Y207558D01*
X756645Y205364D01*
Y195556D01*
X746554Y185465D01*
X743068D01*
X742668Y185865D01*
X738268D01*
X738230Y185827D01*
X729920D01*
G01X724776Y209963D02*
X722990D01*
X722302Y210651D01*
Y211357D01*
X722777Y211831D01*
Y212537D01*
X722068Y213246D01*
X721362D01*
X720887Y212772D01*
X720181D01*
X719472Y213481D01*
Y214187D01*
X719947Y214661D01*
Y215367D01*
X719238Y216076D01*
X718532D01*
X718057Y215602D01*
X717351D01*
X716642Y216311D01*
Y217017D01*
X717117Y217491D01*
Y218197D01*
X716408Y218906D01*
X715702D01*
X715227Y218432D01*
X714521D01*
X712056Y220897D01*
Y221605D01*
X712556Y222105D01*
Y222813D01*
X711849Y223520D01*
X711141D01*
X710641Y223020D01*
X709933D01*
X708708Y224245D01*
Y225953D01*
X709208Y226453D01*
X710044D01*
X710544Y226953D01*
Y227953D01*
X710044Y228453D01*
X709208D01*
X708708Y228953D01*
Y229953D01*
X709208Y230453D01*
X710044D01*
X710544Y230953D01*
Y231953D01*
X710044Y232453D01*
X709208D01*
X708708Y232953D01*
Y233953D01*
X709208Y234453D01*
X710044D01*
X710544Y234953D01*
Y235953D01*
X710044Y236453D01*
X709208D01*
X708708Y236953D01*
Y244294D01*
X709208Y244794D01*
X710085D01*
X710585Y245294D01*
Y246294D01*
X710085Y246794D01*
X709208D01*
X708708Y247294D01*
Y248294D01*
X709208Y248794D01*
X710085D01*
X710585Y249294D01*
Y250294D01*
X710085Y250794D01*
X709208D01*
X708708Y251294D01*
Y252294D01*
X709208Y252794D01*
X710085D01*
X710585Y253294D01*
Y254294D01*
X710085Y254794D01*
X709208D01*
X708708Y255294D01*
Y256294D01*
X709208Y256794D01*
X710085D01*
X710585Y257294D01*
Y258294D01*
X710085Y258794D01*
X709208D01*
X708708Y259294D01*
Y260294D01*
X709208Y260794D01*
X709856D01*
X710356Y261294D01*
Y262294D01*
X709856Y262794D01*
X709208D01*
X708708Y263294D01*
Y263990D01*
X718199Y273481D01*
Y274189D01*
X717492Y274896D01*
X716784D01*
X710160Y268272D01*
X709452D01*
X708745Y268979D01*
Y269687D01*
X726669Y287611D01*
X731300D01*
G01X761638Y259635D02*
X764596D01*
X768637Y255594D01*
Y252028D01*
X774146Y246519D01*
Y245638D01*
X773646Y245138D01*
X770936D01*
X770436Y244638D01*
Y243638D01*
X770936Y243138D01*
X773157D01*
X773657Y242638D01*
Y241638D01*
X773157Y241138D01*
X770936D01*
X770436Y240638D01*
Y239638D01*
X770936Y239138D01*
X773303D01*
X773803Y238638D01*
Y237638D01*
X773303Y237138D01*
X770936D01*
X770436Y236638D01*
Y235638D01*
X770936Y235138D01*
X773313D01*
X773813Y234638D01*
Y233638D01*
X773313Y233138D01*
X770936D01*
X770436Y232638D01*
Y231638D01*
X770936Y231138D01*
X773313D01*
X773813Y230638D01*
Y229638D01*
X773313Y229138D01*
X770936D01*
X770436Y228638D01*
Y227638D01*
X770936Y227138D01*
X773646D01*
X774146Y226638D01*
Y225990D01*
X772511Y224355D01*
X768219D01*
X756839Y212975D01*
Y208387D01*
X754645Y206193D01*
Y196385D01*
X745375Y187115D01*
X743752D01*
G01X742502Y182715D02*
X743252Y183465D01*
X747383D01*
X758645Y194727D01*
Y204535D01*
X764569Y210459D01*
Y214550D01*
X769484Y219465D01*
X773316D01*
X778725Y224874D01*
Y242741D01*
X779225Y243241D01*
X780091D01*
X780591Y243741D01*
Y244741D01*
X780091Y245241D01*
X779225D01*
X778725Y245741D01*
Y246741D01*
X779225Y247241D01*
X780091D01*
X780591Y247741D01*
Y248741D01*
X780091Y249241D01*
X779225D01*
X778725Y249741D01*
Y250741D01*
X779225Y251241D01*
X780091D01*
X780591Y251741D01*
Y252741D01*
X780091Y253241D01*
X779225D01*
X778725Y253741D01*
Y255658D01*
X774637Y259746D01*
G01Y263746D02*
X776295D01*
X784837Y255204D01*
Y222095D01*
X766839Y204097D01*
Y194434D01*
X749420Y177015D01*
X742252D01*
G01X720819Y209800D02*
X720324D01*
X715673Y214451D01*
X714965D01*
X713336Y212822D01*
X712628D01*
X711921Y213529D01*
Y214237D01*
X713550Y215866D01*
Y216574D01*
X712843Y217281D01*
X712135D01*
X710506Y215652D01*
X709798D01*
X709091Y216359D01*
Y217067D01*
X710720Y218696D01*
Y219404D01*
X710013Y220111D01*
X709305D01*
X708291Y219097D01*
X707583D01*
X706876Y219804D01*
Y220512D01*
X707890Y221526D01*
Y222234D01*
X706708Y223416D01*
Y270479D01*
X729115Y292886D01*
X736468D01*
X736968Y293386D01*
Y294386D01*
X736468Y294886D01*
X733300D01*
X732800Y295386D01*
Y296386D01*
X733300Y296886D01*
X736406D01*
X736906Y297386D01*
Y300386D01*
X737406Y300886D01*
X738781D01*
X739281Y300386D01*
Y290135D01*
X738781Y289635D01*
X735800D01*
X735300Y289135D01*
Y287611D01*
G01X731318Y283571D02*
X728287D01*
X722421Y277705D01*
Y269775D01*
X718587Y265941D01*
Y237529D01*
X718087Y237029D01*
X717087D01*
X716587Y237529D01*
Y262454D01*
X716087Y262954D01*
X715087D01*
X714587Y262454D01*
Y226775D01*
X715087Y226275D01*
X716087D01*
X716587Y226775D01*
Y231986D01*
X717087Y232486D01*
X718087D01*
X718587Y231986D01*
Y222552D01*
X729246Y211893D01*
Y209941D01*
G01X735318Y283571D02*
Y283511D01*
X735378D01*
X736587Y282302D01*
Y254479D01*
X736087Y253979D01*
X735087D01*
X734587Y254479D01*
Y272816D01*
X734087Y273316D01*
X733087D01*
X732587Y272816D01*
Y237599D01*
X732087Y237099D01*
X729087D01*
X728587Y236599D01*
Y233368D01*
X729087Y232868D01*
X732051D01*
X732551Y232368D01*
Y231368D01*
X732051Y230868D01*
X729087D01*
X728587Y230368D01*
Y229368D01*
X729087Y228868D01*
X732087D01*
X732587Y228368D01*
Y217238D01*
X733087Y216738D01*
X734087D01*
X734587Y217238D01*
Y220302D01*
X735087Y220802D01*
X736087D01*
X736587Y220302D01*
Y208496D01*
X736272Y208181D01*
G01X731155Y279636D02*
X727181D01*
X724587Y277042D01*
Y239321D01*
X724087Y238821D01*
X723087D01*
X722587Y239321D01*
Y262571D01*
X722087Y263071D01*
X721087D01*
X720587Y262571D01*
Y224064D01*
X721087Y223564D01*
X722087D01*
X722587Y224064D01*
Y231472D01*
X723087Y231972D01*
X724087D01*
X724587Y231472D01*
Y227236D01*
X726315Y225508D01*
Y221739D01*
X726815Y221239D01*
X727986D01*
X728486Y220739D01*
Y219739D01*
X727986Y219239D01*
X726815D01*
X726315Y218739D01*
Y217852D01*
X730896Y213271D01*
Y208414D01*
X729136Y206654D01*
G01X739318Y283571D02*
X740818D01*
X741318Y284071D01*
Y300304D01*
X741818Y300804D01*
X746230D01*
X746730Y300304D01*
Y299304D01*
X746230Y298804D01*
X744276D01*
X743776Y298304D01*
Y297304D01*
X744276Y296804D01*
X746230D01*
X746730Y296304D01*
Y295304D01*
X746230Y294804D01*
X744276D01*
X743776Y294304D01*
Y293304D01*
X744276Y292804D01*
X746230D01*
X746730Y292304D01*
Y291304D01*
X746230Y290804D01*
X744276D01*
X743776Y290304D01*
Y289304D01*
X744276Y288804D01*
X746230D01*
X746730Y288304D01*
Y287304D01*
X746230Y286804D01*
X744276D01*
X743776Y286304D01*
Y285304D01*
X744276Y284804D01*
X746230D01*
X746730Y284304D01*
Y283304D01*
X746230Y282804D01*
X743818D01*
X743318Y282304D01*
Y278611D01*
X742818Y278111D01*
X741818D01*
X741318Y278611D01*
Y279924D01*
X740818Y280424D01*
X739818D01*
X739318Y279924D01*
Y254080D01*
X735871Y250633D01*
Y236748D01*
X734603Y235480D01*
Y225147D01*
X738839Y220911D01*
Y206080D01*
G01X733565Y210184D02*
Y213431D01*
X730587Y216409D01*
Y221963D01*
X728844Y223706D01*
Y226282D01*
X726587Y228539D01*
Y232696D01*
X724806Y234477D01*
Y236152D01*
X726587Y237933D01*
Y275165D01*
X727087Y275665D01*
X728087D01*
X728587Y275165D01*
Y240142D01*
X729087Y239642D01*
X730087D01*
X730587Y240142D01*
Y275196D01*
X731087Y275696D01*
X734638D01*
G01X729920Y192126D02*
X730225Y192431D01*
X739273D01*
X743198Y196356D01*
Y202837D01*
X744741Y204380D01*
Y210660D01*
X746839Y212758D01*
Y222858D01*
X755558Y231577D01*
Y246103D01*
X759558Y250103D01*
Y270149D01*
X759058Y270649D01*
X750193D01*
X749693Y270149D01*
Y269149D01*
X750193Y268649D01*
X756974D01*
X757474Y268149D01*
Y267149D01*
X756974Y266649D01*
X750193D01*
X749693Y266149D01*
Y265149D01*
X750193Y264649D01*
X756890D01*
X757390Y264149D01*
Y263149D01*
X756890Y262649D01*
X752193D01*
X751693Y262149D01*
Y259540D01*
G01X704724Y201574D02*
X705140D01*
X708658Y205092D01*
Y207641D01*
X702583Y213716D01*
Y254522D01*
X704708Y256647D01*
G01Y252647D02*
Y216811D01*
X714173Y207346D01*
Y201574D01*
G01X761650Y89937D02*
X762090Y90377D01*
X774737D01*
X798850Y114490D01*
Y136086D01*
X796248Y138688D01*
Y208952D01*
X795064Y210136D01*
Y243317D01*
X791657Y246724D01*
Y277732D01*
X786006Y283383D01*
G01X775486Y287316D02*
X779684D01*
X783505Y283495D01*
Y282348D01*
X789157Y276696D01*
Y245687D01*
X790620Y244224D01*
X790621D01*
X792564Y242281D01*
Y209036D01*
X793748Y207852D01*
Y137652D01*
X796350Y135050D01*
Y115528D01*
X773862Y93040D01*
X771610D01*
G01X767359Y82076D02*
X772804Y87521D01*
X775435D01*
X801350Y113436D01*
Y138619D01*
X798762Y141207D01*
Y210038D01*
X797564Y211236D01*
Y287714D01*
X795432Y289846D01*
X765508D01*
X763292Y287630D01*
G01X801728Y304572D02*
Y303433D01*
X799564Y301269D01*
Y212170D01*
X801618Y210116D01*
G01Y214116D02*
Y300280D01*
X801853Y300515D01*
G54D11*
G01X-34018Y-300855D02*
G02I-12000J0D01*
G01X-39168D02*
G02I-6850J0D01*
G01X-30018D02*
X-62018D01*
G01X-30018Y-316855D02*
Y-396855D01*
G01D02*
X1320682D01*
G01X-30018Y-352355D02*
X1320682D01*
G01X-46018Y-316855D02*
Y-284855D01*
G01X-30018Y-316855D02*
X1320682D01*
G01X64000Y178400D02*
Y176100D01*
X65800Y174300D01*
X71400D01*
X72800Y175700D01*
Y178200D01*
G01X40290Y239814D02*
X46704Y233400D01*
X58600D01*
X66400Y225600D01*
Y183900D01*
X64000Y181500D01*
Y178400D01*
G01X72800Y178200D02*
Y181400D01*
X74215Y182815D01*
X88685D01*
X89800Y181700D01*
Y178000D01*
G01D02*
Y147850D01*
X84672Y142722D01*
Y138471D01*
G01X533182Y-316855D02*
Y-396855D01*
G01X670682Y-316855D02*
Y-396855D01*
G01X644500Y65759D02*
X652005D01*
X655964Y61800D01*
Y52248D01*
G01X785682Y-316855D02*
Y-396855D01*
G01X953182Y-316855D02*
Y-396855D01*
G01X1123182Y-316855D02*
Y-396855D01*
G01X1320682Y-316855D02*
Y-396855D01*
G01X1348682Y-300855D02*
G02I-12000J0D01*
G01X1343532D02*
G02I-6850J0D01*
G01X1336682Y-316855D02*
Y-284855D01*
G01X1352682Y-300855D02*
X1320682D01*
X64000Y178400D03*
X72800Y178200D03*
X45650Y250280D03*
X49320D03*
X40290Y239814D03*
X32469Y250280D03*
X37469D03*
X58900Y334180D03*
X62325Y334068D03*
X37900Y334380D03*
X41325Y334268D03*
X35800Y363400D03*
X40100D03*
X89800Y178000D03*
X80688Y281695D03*
Y276695D03*
X93884Y242333D03*
X102300Y329100D03*
X80700Y309400D03*
X80600Y304600D03*
Y334580D03*
X84025Y334468D03*
X102400Y333900D03*
X106500D03*
X85795Y378426D03*
X106709Y383400D03*
X112023Y383013D03*
X104900Y412200D03*
X107582Y391266D03*
X164020Y101127D03*
X197100Y298800D03*
X196600Y306800D03*
X250137Y36053D03*
X255300Y72600D03*
X255154Y69177D03*
X233759Y64752D03*
X204400Y288700D03*
X248900Y282932D03*
X259629Y281000D03*
X242351Y282900D03*
X228300Y280900D03*
X219400Y279400D03*
X212198Y328316D03*
X208648Y328452D03*
X261365Y324351D03*
X245943Y326300D03*
X246100Y329700D03*
X230400Y326200D03*
Y329600D03*
X218400Y326600D03*
X218300Y330000D03*
X259800Y423400D03*
X311182Y58692D03*
X276700Y66700D03*
X283385Y100227D03*
X287385D03*
X319533Y114283D03*
X291385Y100227D03*
X295385D03*
X306196Y110209D03*
X310711Y113820D03*
X314772Y108292D03*
X311182Y62800D03*
X272937Y90362D03*
X266895Y100227D03*
X283393Y92325D03*
X272937Y85862D03*
X318773Y108083D03*
X278039Y82185D03*
X292385Y108227D03*
X280298Y95556D03*
X324026Y115936D03*
X321343Y122343D03*
X321051Y134028D03*
X304529Y118792D03*
X268400Y281000D03*
X306292Y252825D03*
X302262Y262642D03*
X265365Y324351D03*
X288536Y314764D03*
X275696Y314340D03*
X266500Y364000D03*
X328600Y114400D03*
X328711Y108053D03*
X335722Y94574D03*
X329722D03*
X374616Y172378D03*
X370061Y172433D03*
X355500Y144500D03*
X342000Y141600D03*
X331649Y126111D03*
X339049Y124238D03*
X335994Y126119D03*
X341913Y145049D03*
X374915Y176442D03*
X359969Y124510D03*
X349911Y136954D03*
X376306Y182715D03*
X351723Y178499D03*
X354143Y183439D03*
X362260Y184360D03*
X364169Y188366D03*
X366460Y191794D03*
X368558Y194540D03*
X379415Y194608D03*
X370570Y198219D03*
X371124Y178760D03*
X372517Y182362D03*
X380400Y287400D03*
X382000Y296500D03*
X384600Y285600D03*
X379000Y272600D03*
X384300Y291100D03*
X343100Y281300D03*
X385887Y305222D03*
X381396Y302610D03*
X344000Y316000D03*
X346500Y302500D03*
X364050Y337200D03*
X374250Y347600D03*
X359200Y315800D03*
X360300Y323900D03*
X360000Y410000D03*
X401700Y337350D03*
X392959Y337099D03*
X405921Y347159D03*
X430464Y347078D03*
X390550Y326820D03*
X405783Y339318D03*
X448500Y424000D03*
X445000Y422000D03*
X468500Y347500D03*
X476200Y334900D03*
X506262Y348500D03*
X510138D03*
X452500Y423500D03*
X510700Y367309D03*
X506700D03*
X546627Y324049D03*
X551127D03*
X545278Y315738D03*
X549778D03*
X545221Y308771D03*
X549721D03*
X545193Y301280D03*
X549693D03*
X519263Y327092D03*
X538476Y334365D03*
X538436Y330918D03*
X534100Y342410D03*
X536200Y348300D03*
X540200D03*
X550100D03*
X546100D03*
X554685Y333410D03*
X547927Y342199D03*
X543646Y342347D03*
X539446D03*
X519629Y330448D03*
X521914Y332907D03*
X574250Y466900D03*
X627500Y19339D03*
X634400Y102000D03*
X630600D03*
X635852Y133715D03*
X636363Y209944D03*
X632363D03*
X628363D03*
X624363D03*
X629250Y310491D03*
Y306491D03*
X626405Y314991D03*
X629250Y344900D03*
Y348900D03*
X623063Y357337D03*
X624200Y372500D03*
X620260Y389940D03*
X588400Y469450D03*
X581250Y480550D03*
X643103Y13803D03*
X638103Y13100D03*
X647103Y13964D03*
X694365Y94458D03*
Y90958D03*
X686279Y94494D03*
Y90994D03*
X678225Y94496D03*
Y90996D03*
X670146Y94505D03*
Y91005D03*
X662047Y94539D03*
Y91039D03*
X654037Y94708D03*
Y91208D03*
X644500Y65759D03*
X657480Y113385D03*
X678189Y108784D03*
X689049Y109487D03*
X669500Y108400D03*
X640600Y111600D03*
X673229Y170079D03*
X679527Y173229D03*
X692126Y141732D03*
X698425D03*
X679527Y148031D03*
X685826D03*
X692126D03*
X698425D03*
X679527Y154330D03*
X685826D03*
X692126D03*
X698425D03*
Y160629D03*
X692126D03*
X685826D03*
X679527D03*
X698425Y166929D03*
X692126D03*
X685826D03*
X679527D03*
X698425Y173228D03*
X692126D03*
X685826D03*
X676376Y132281D03*
X666929Y129134D03*
X644882Y154331D03*
X637952Y142515D03*
X640500Y125000D03*
X660629Y144883D03*
X657481Y132284D03*
X686352Y207200D03*
X640363Y209944D03*
X638479Y230640D03*
X697149Y219742D03*
X692949D03*
X644153Y278745D03*
X680300Y384900D03*
X654770Y401166D03*
X671640Y454410D03*
X683250Y437813D03*
X710378Y96399D03*
Y92899D03*
X702391Y94510D03*
Y91010D03*
X745100Y97500D03*
X699563Y108815D03*
X704724Y148031D03*
Y154330D03*
Y160629D03*
Y166929D03*
Y173228D03*
X714173Y122834D03*
X720472D03*
X741077Y159790D03*
X757471Y148193D03*
X723621Y148031D03*
Y154330D03*
Y160629D03*
Y166929D03*
Y173228D03*
X707874Y122835D03*
X723621Y135433D03*
Y129133D03*
Y141732D03*
X741952Y173115D03*
X701574Y192125D03*
X707873D03*
X714173D03*
X723621D03*
Y185826D03*
Y179527D03*
X725009Y213292D03*
X739852Y195915D03*
X737832Y202664D03*
X729920Y188977D03*
X739752Y199615D03*
X738416Y190551D03*
X729920Y182678D03*
X745485Y197673D03*
Y201673D03*
X740352Y180115D03*
X729920Y185827D03*
X724776Y209963D03*
X743752Y187115D03*
X742502Y182715D03*
X742252Y177015D03*
X720819Y209800D03*
X729246Y209941D03*
X736272Y208181D03*
X729136Y206654D03*
X738839Y206080D03*
X733565Y210184D03*
X729920Y192126D03*
X704724Y201574D03*
X714173D03*
X704708Y264647D03*
X739300Y287611D03*
X751693Y255540D03*
X743507Y251685D03*
X747558Y247274D03*
X759558Y241027D03*
Y247274D03*
X731300Y287611D03*
X735300D03*
X731318Y283571D03*
X735318D03*
X731155Y279636D03*
X739318Y283571D03*
X734638Y275696D03*
X751693Y259540D03*
X704708Y256647D03*
Y252647D03*
X700200Y388200D03*
Y384800D03*
X743480Y439080D03*
X706120Y441410D03*
X729870Y451300D03*
X761650Y89937D03*
X771610Y93040D03*
X767359Y82076D03*
X760800Y169550D03*
X769600Y164200D03*
X765200Y135750D03*
X786500Y134283D03*
X763050Y154100D03*
X761400Y160050D03*
X764600Y141500D03*
X764550Y182900D03*
X764750Y179300D03*
X761550Y180500D03*
X790714Y237308D03*
X801618Y210116D03*
Y214116D03*
X786006Y283383D03*
X775486Y287316D03*
X805254Y263886D03*
X761484Y255581D03*
Y251581D03*
X780837Y240885D03*
X774637Y267746D03*
X770637D03*
X761638Y259635D03*
X774637Y259746D03*
Y263746D03*
X801853Y300515D03*
X763292Y287630D03*
X765764Y326844D03*
X801728Y304572D03*
G54D21*
G01X409449Y204725D02*
Y203481D01*
G03X409799Y203131I350J0D01*
G01X410442D01*
G02X411808Y201765I0J-1366D01*
G01Y199294D01*
X412033Y199069D01*
Y198982D01*
G01X409449Y200788D02*
Y202031D01*
G02X409799Y202381I350J0D01*
G01X410442D01*
G02X411058Y201765I0J-616D01*
G01Y199294D01*
X410833Y199069D01*
Y198982D01*
G01X413386Y208662D02*
Y207418D01*
G03X413736Y207068I350J0D01*
G01X414370D01*
G02X415329Y206672I0J-1359D01*
G01X415331Y206670D01*
G02X415728Y205709I-965J-961D01*
G01Y199225D01*
X415953Y199000D01*
Y198913D01*
G01X413386Y204725D02*
Y205968D01*
G02X413736Y206318I350J0D01*
G01X414370D01*
G02X414799Y206141I0J-608D01*
G01X414800Y206140D01*
G02X414978Y205709I-433J-431D01*
G01Y199225D01*
X414753Y199000D01*
Y198913D01*
G01X417323Y204725D02*
Y203481D01*
G03X417673Y203131I350J0D01*
G01X418099D01*
G02X419219Y202668I1J-1583D01*
G02X419682Y201548I-1120J-1119D01*
G01Y199294D01*
X419907Y199069D01*
Y198982D01*
G01X417323Y200788D02*
Y202031D01*
G02X417673Y202381I350J0D01*
G01X418099D01*
G02X418688Y202137I0J-833D01*
G02X418932Y201548I-589J-589D01*
G01Y199294D01*
X418707Y199069D01*
Y198982D01*
G01X421260Y208662D02*
Y207418D01*
G03X421610Y207068I350J0D01*
G01X422101D01*
G02X423163Y206629I1J-1501D01*
G02X423602Y205567I-1062J-1061D01*
G01Y199225D01*
X423827Y199000D01*
Y198913D01*
G01X421260Y204725D02*
Y205968D01*
G02X421610Y206318I350J0D01*
G01X422101D01*
G02X422632Y206098I0J-751D01*
G02X422852Y205567I-531J-531D01*
G01Y199225D01*
X422627Y199000D01*
Y198913D01*
G01X396279Y199348D02*
Y199435D01*
X396054Y199660D01*
Y201769D01*
G03X395657Y202730I-1363J-1D01*
G01X395581Y202806D01*
G03X394798Y203131I-781J-775D01*
G01X394051D01*
G02X393701Y203481I0J350D01*
G01Y204725D01*
G01X395079Y199348D02*
Y199435D01*
X395304Y199660D01*
Y201768D01*
G03X395124Y202201I-613J-1D01*
G01X395048Y202278D01*
G03X394799Y202381I-248J-247D01*
G01X394051D01*
G03X393701Y202031I0J-350D01*
G01Y200788D01*
G01X397638Y208662D02*
Y207418D01*
G03X397988Y207068I350J0D01*
G01X398615D01*
G02X399581Y206669I1J-1366D01*
G02X399980Y205703I-967J-965D01*
G01Y199225D01*
X400205Y199000D01*
Y198913D01*
G01X397638Y204725D02*
Y205968D01*
G02X397988Y206318I350J0D01*
G01X398615D01*
G02X399050Y206138I0J-616D01*
G02X399230Y205703I-436J-435D01*
G01Y199225D01*
X399005Y199000D01*
Y198913D01*
G01X401575Y204725D02*
Y203481D01*
G03X401925Y203131I350J0D01*
G01X402638D01*
G02X403555Y202752I1J-1296D01*
G02X403934Y201835I-917J-916D01*
G01Y199294D01*
X404159Y199069D01*
Y198982D01*
G01X401575Y200788D02*
Y202031D01*
G02X401925Y202381I350J0D01*
G01X402638D01*
G02X403024Y202221I0J-546D01*
G02X403184Y201835I-386J-386D01*
G01Y199294D01*
X402959Y199069D01*
Y198982D01*
G01X405512Y208662D02*
Y207418D01*
G03X405862Y207068I350J0D01*
G01X406517D01*
G02X407463Y206677I1J-1337D01*
G02X407854Y205731I-946J-945D01*
G01Y199225D01*
X408079Y199000D01*
Y198913D01*
G01X405512Y204725D02*
Y205968D01*
G02X405862Y206318I350J0D01*
G01X406517D01*
G02X406932Y206146I0J-587D01*
G02X407104Y205731I-415J-415D01*
G01Y199225D01*
X406879Y199000D01*
Y198913D01*
G01X425197Y204725D02*
Y203481D01*
G03X425547Y203131I350J0D01*
G01X426244D01*
G02X427173Y202746I0J-1313D01*
G02X427556Y201820I-928J-926D01*
G01Y199294D01*
X427781Y199069D01*
Y198982D01*
G01X425197Y200788D02*
Y202031D01*
G02X425547Y202381I350J0D01*
G01X426244D01*
G02X426642Y202216I0J-563D01*
G02X426806Y201820I-396J-396D01*
G01Y199294D01*
X426581Y199069D01*
Y198982D01*
G01X429134Y208662D02*
Y207418D01*
G03X429484Y207068I350J0D01*
G01X430343D01*
G02X431143Y206737I0J-1132D01*
G02X431476Y205934I-802J-803D01*
G01Y199225D01*
X431701Y199000D01*
Y198913D01*
G01X429134Y204725D02*
Y205968D01*
G02X429484Y206318I350J0D01*
G01X430343D01*
G02X430613Y206206I0J-381D01*
G02X430726Y205934I-271J-272D01*
G01Y199225D01*
X430501Y199000D01*
Y198913D01*
G01X433071Y204725D02*
Y203481D01*
G03X433421Y203131I350J0D01*
G01X434267D01*
G02X435090Y202791I1J-1163D01*
G02X435430Y201968I-823J-822D01*
G01Y199294D01*
X435655Y199069D01*
Y198982D01*
G01X433071Y200788D02*
Y202031D01*
G02X433421Y202381I350J0D01*
G01X434267D01*
G02X434559Y202260I0J-413D01*
G02X434680Y201968I-292J-292D01*
G01Y199294D01*
X434455Y199069D01*
Y198982D01*
G01X437008Y208662D02*
Y207418D01*
G03X437358Y207068I350J0D01*
G01X438064D01*
G02X438974Y206692I1J-1286D01*
G02X439350Y205782I-910J-909D01*
G01Y199225D01*
X439575Y199000D01*
Y198913D01*
G01X437008Y204725D02*
Y205968D01*
G02X437358Y206318I350J0D01*
G01X438064D01*
G02X438443Y206161I0J-536D01*
G02X438600Y205782I-379J-379D01*
G01Y199225D01*
X438375Y199000D01*
Y198913D01*
G01X440945Y204725D02*
Y203481D01*
G03X441295Y203131I350J0D01*
G01X442036D01*
G02X442933Y202761I2J-1267D01*
G01X442935Y202759D01*
G02X443304Y201865I-898J-894D01*
G01Y199294D01*
X443529Y199069D01*
Y198982D01*
G01X440945Y200788D02*
Y202031D01*
G02X441295Y202381I350J0D01*
G01X442037D01*
G02X442403Y202229I0J-517D01*
G02X442554Y201865I-366J-365D01*
G01Y199294D01*
X442329Y199069D01*
Y198982D01*
G01X444882Y208662D02*
Y207418D01*
G03X445232Y207068I350J0D01*
G01X445856D01*
G02X446824Y206668I1J-1369D01*
G02X447224Y205700I-969J-967D01*
G01Y199225D01*
X447449Y199000D01*
Y198913D01*
G01X444882Y204725D02*
Y205968D01*
G02X445232Y206318I350J0D01*
G01X445856D01*
G02X446293Y206137I0J-618D01*
G02X446474Y205700I-437J-437D01*
G01Y199225D01*
X446249Y199000D01*
Y198913D01*
G01X448819Y204725D02*
Y203481D01*
G03X449169Y203131I350J0D01*
G01X449936D01*
G02X450829Y202762I1J-1262D01*
G02X451198Y201869I-893J-892D01*
G01Y199294D01*
X451423Y199069D01*
Y198982D01*
G01X448819Y200788D02*
Y202031D01*
G02X449169Y202381I350J0D01*
G01X449936D01*
G02X450298Y202231I0J-512D01*
G02X450448Y201869I-362J-362D01*
G01Y199294D01*
X450223Y199069D01*
Y198982D01*
G01X456693Y208662D02*
Y207418D01*
G03X457043Y207068I350J0D01*
G01X457707D01*
G02X458645Y206682I1J-1330D01*
G01X458647Y206679D01*
G02X459035Y205739I-941J-939D01*
G01Y199225D01*
X459260Y199000D01*
Y198913D01*
G01X456693Y204725D02*
Y205968D01*
G02X457043Y206318I350J0D01*
G01X457707D01*
G02X458115Y206150I0J-579D01*
G01X458116Y206149D01*
G02X458285Y205739I-410J-409D01*
G01Y199225D01*
X458060Y199000D01*
Y198913D01*
G01X460630Y200788D02*
Y202031D01*
G02X460980Y202381I350J0D01*
G01X461717D01*
G02X462086Y202228I0J-521D01*
G02X462239Y201859I-368J-369D01*
G01Y199294D01*
X462014Y199069D01*
Y198982D01*
G01X507874Y240158D02*
X509117D01*
G03X509467Y240508I0J350D01*
G01Y241070D01*
G02X509885Y242081I1429J1D01*
G02X510898Y242500I1012J-1012D01*
G01X512905D01*
G02X514160Y241245I0J-1255D01*
G01Y237583D01*
X514458Y237285D01*
Y237198D01*
G01X513258D02*
Y237285D01*
X513410Y237437D01*
Y241245D01*
G03X512905Y241750I-505J0D01*
G01X510898D01*
G03X510416Y241550I0J-681D01*
G03X510217Y241070I479J-480D01*
G01Y240508D01*
G03X510567Y240158I350J0D01*
G01X511811D01*
G01X460630Y204725D02*
Y203481D01*
G03X460980Y203131I350J0D01*
G01X461717D01*
G02X462617Y202759I1J-1272D01*
G02X462989Y201859I-900J-899D01*
G01Y199294D01*
X463214Y199069D01*
Y198982D01*
G01X467134Y198913D02*
Y199000D01*
X466909Y199225D01*
Y205864D01*
G03X466557Y206716I-1204J1D01*
G03X465705Y207068I-851J-852D01*
G01X464917D01*
G02X464567Y207418I0J350D01*
G01Y208662D01*
G01X465934Y198913D02*
Y199000D01*
X466159Y199225D01*
Y205864D01*
G03X466026Y206185I-454J0D01*
G03X465705Y206318I-321J-321D01*
G01X464917D01*
G03X464567Y205968I0J-350D01*
G01Y204725D01*
G01X468504D02*
Y203481D01*
G03X468854Y203131I350J0D01*
G01X469597D01*
G02X470380Y202806I2J-1100D01*
G01X470460Y202725D01*
G02X470863Y201752I-977J-975D01*
G01Y199294D01*
X471088Y199069D01*
Y198621D01*
G01X468504Y200788D02*
Y202031D01*
G02X468854Y202381I350J0D01*
G01X469598D01*
G02X469847Y202278I1J-350D01*
G01X469928Y202196D01*
G02X470113Y201751I-445J-446D01*
G01Y199294D01*
X469888Y199069D01*
Y198982D01*
G01X475008Y198913D02*
Y199000D01*
X474783Y199225D01*
Y205818D01*
G03X474416Y206703I-1251J0D01*
G03X473534Y207068I-882J-883D01*
G01X472791D01*
G02X472441Y207418I0J350D01*
G01Y208662D01*
G01X473808Y198913D02*
Y199000D01*
X474033Y199225D01*
Y205818D01*
G03X473886Y206172I-500J0D01*
G03X473534Y206318I-352J-351D01*
G01X472791D01*
G03X472441Y205968I0J-350D01*
G01Y204725D01*
G01X476378D02*
Y203481D01*
G03X476728Y203131I350J0D01*
G01X477079D01*
G02X478209Y202664I1J-1598D01*
G01X478240Y202632D01*
G02X478737Y201430I-1205J-1202D01*
G01Y199294D01*
X478962Y199069D01*
Y198982D01*
G01X476378Y200788D02*
Y202031D01*
G02X476728Y202381I350J0D01*
G01X477079D01*
G02X477678Y202133I0J-847D01*
G01X477709Y202102D01*
G02X477987Y201430I-673J-672D01*
G01Y199294D01*
X477762Y199069D01*
Y198982D01*
G01X480315Y208662D02*
Y207418D01*
G03X480665Y207068I350J0D01*
G01X481089D01*
G02X482204Y206607I1J-1576D01*
G02X482665Y205492I-1115J-1114D01*
G01Y199572D01*
X482890Y199347D01*
Y199260D01*
G01X480315Y204725D02*
Y205968D01*
G02X480665Y206318I350J0D01*
G01X481089D01*
G02X481673Y206076I0J-826D01*
G02X481915Y205492I-584J-584D01*
G01Y199572D01*
X481690Y199347D01*
Y199260D01*
G01X484252Y204725D02*
Y203481D01*
G03X484602Y203131I350J0D01*
G01X501334D01*
X502350Y202115D01*
Y199694D01*
X502575Y199469D01*
Y199382D01*
G01X501375D02*
Y199469D01*
X501600Y199694D01*
Y201804D01*
X501023Y202381D01*
X484602D01*
G03X484252Y202031I0J-350D01*
G01Y200788D01*
G01X488189Y208662D02*
Y207418D01*
G03X488539Y207068I350J0D01*
G01X505271D01*
X506296Y206043D01*
Y199982D01*
X507078Y199200D01*
X508875D01*
X509100Y199425D01*
X509187D01*
G01X488189Y204725D02*
Y205968D01*
G02X488539Y206318I350J0D01*
G01X504960D01*
X505546Y205732D01*
Y199671D01*
X506767Y198450D01*
X508875D01*
X509100Y198225D01*
X509187D01*
G01X515748Y244095D02*
X514504D01*
G02X514154Y244445I0J350D01*
G01Y245212D01*
G02X514294Y245550I478J0D01*
G02X514632Y245690I338J-338D01*
G01X517296D01*
X517521Y245465D01*
X517608D01*
G01X507874Y255906D02*
X509117D01*
G03X509467Y256256I0J350D01*
G01Y256973D01*
G02X509842Y257877I1277J0D01*
G02X510744Y258250I902J-904D01*
G01X517775D01*
X518000Y258475D01*
X518087D01*
G01X511811Y255906D02*
X510567D01*
G02X510217Y256256I0J350D01*
G01Y256973D01*
G02X510372Y257346I526J0D01*
G02X510744Y257500I372J-372D01*
G01X517775D01*
X518000Y257275D01*
X518087D01*
G01X507874Y267717D02*
X509112D01*
G03X509462Y268067I0J350D01*
G01Y268501D01*
G02X509918Y269604I1559J1D01*
G02X511021Y270060I1102J-1103D01*
G01X516575D01*
X516800Y270285D01*
X516887D01*
G01X511811Y267717D02*
X510562D01*
G02X510212Y268067I0J350D01*
G01Y268501D01*
G02X510449Y269073I809J0D01*
G02X511021Y269310I572J-572D01*
G01X516575D01*
X516800Y269085D01*
X516887D01*
G01X517121Y250595D02*
X517034D01*
X516809Y250370D01*
X510924D01*
G03X509893Y249944I-1J-1458D01*
G03X509467Y248913I1032J-1030D01*
G01Y248382D01*
G02X509117Y248032I-350J0D01*
G01X507874D01*
G01X511811D02*
X510567D01*
G02X510217Y248382I0J350D01*
G01Y248913D01*
G02X510424Y249413I707J0D01*
G02X510924Y249620I500J-500D01*
G01X516809D01*
X517034Y249395D01*
X517121D01*
G01X507874Y275591D02*
X509117D01*
G03X509467Y275941I0J350D01*
G01Y276613D01*
G02X509854Y277547I1321J0D01*
G02X510785Y277932I931J-933D01*
G01X516881D01*
X517106Y278157D01*
X517554D01*
G01X517193Y276957D02*
X517106D01*
X516881Y277182D01*
X510785D01*
G03X510384Y277016I0J-567D01*
G03X510217Y276613I403J-403D01*
G01Y275941D01*
G03X510567Y275591I350J0D01*
G01X511811D01*
G01X507874Y283465D02*
X509117D01*
G03X509467Y283815I0J350D01*
G01Y284565D01*
G02X509792Y285349I1100J3D01*
G01X509859Y285415D01*
G02X510798Y285803I940J-944D01*
G01X516827D01*
X517052Y286028D01*
X517139D01*
G01X511811Y283465D02*
X510567D01*
G02X510217Y283815I0J350D01*
G01Y284566D01*
G02X510320Y284815I350J1D01*
G01X510388Y284882D01*
G02X510799Y285053I412J-411D01*
G01X516827D01*
X517052Y284828D01*
X517500D01*
G01X511811Y259843D02*
X513054D01*
G03X513404Y260193I0J350D01*
G01Y261741D01*
G02X514738Y263075I1334J0D01*
G01X515897D01*
X516122Y263300D01*
X516209D01*
G01X515748Y259843D02*
X514504D01*
G02X514154Y260193I0J350D01*
G01Y261741D01*
G02X514738Y262325I584J0D01*
G01X515897D01*
X516122Y262100D01*
X516209D01*
G01X511811Y244095D02*
X513054D01*
G03X513404Y244445I0J350D01*
G01Y245212D01*
G02X513763Y246081I1228J1D01*
G02X514632Y246440I868J-869D01*
G01X517296D01*
X517521Y246665D01*
X517608D01*
G01X511811Y271654D02*
X512954D01*
G03X513304Y272004I0J350D01*
G01Y272544D01*
G02X513731Y273577I1460J1D01*
G02X514764Y274004I1032J-1033D01*
G01X517086D01*
X517377Y274295D01*
X517464D01*
G01X515748Y271654D02*
X514404D01*
G02X514054Y272004I0J350D01*
G01Y272544D01*
G02X514262Y273046I710J0D01*
G02X514764Y273254I502J-502D01*
G01X517218D01*
X517377Y273095D01*
X517464D01*
G01X511811Y251969D02*
X513054D01*
G03X513404Y252319I0J350D01*
G01Y252847D01*
G02X513831Y253882I1462J2D01*
G01X513833Y253884D01*
G02X514865Y254310I1032J-1037D01*
G01X517753D01*
X517978Y254535D01*
X518065D01*
G01Y253335D02*
X517978D01*
X517753Y253560D01*
X514865D01*
G03X514363Y253353I0J-712D01*
G01X514362Y253352D01*
G03X514154Y252848I504J-503D01*
G01Y252319D01*
G03X514504Y251969I350J0D01*
G01X515748D01*
G01X517198Y282103D02*
X517111D01*
X516886Y281878D01*
X514687D01*
G03X513781Y281504I0J-1284D01*
G01X513779Y281502D01*
G03X513404Y280593I910J-907D01*
G01Y279878D01*
G02X513054Y279528I-350J0D01*
G01X511811D01*
G01X517559Y280903D02*
X517111D01*
X516886Y281128D01*
X514687D01*
G03X514311Y280973I0J-534D01*
G01X514310Y280972D01*
G03X514154Y280594I379J-378D01*
G01Y279878D01*
G03X514504Y279528I350J0D01*
G01X515748D01*
G01X511811Y287402D02*
X513054D01*
G03X513404Y287752I0J350D01*
G01Y289550D01*
X513254Y289700D01*
Y289787D01*
G01X515748Y287402D02*
X514504D01*
G02X514154Y287752I0J350D01*
G01Y289300D01*
X514454Y289600D01*
Y289787D01*
G54D12*
X84672Y138471D03*
G54D22*
G01X708661Y20473D02*
Y19023D01*
G02X708006Y18368I-655J0D01*
G01X705909D01*
X704428Y18683D01*
X703413Y19342D01*
X702526Y20709D01*
X701636Y22078D01*
Y22077D01*
X697388Y42059D01*
X684555Y61814D01*
X665609Y74590D01*
X655691Y77963D01*
X655078Y79554D01*
X654842Y80166D01*
X654773Y80349D01*
X654759Y80386D01*
X654742Y80430D01*
X654553Y80919D01*
X654489Y81084D01*
X654849Y83016D01*
X656587Y85295D01*
X658326Y87574D01*
X658881Y89952D01*
Y90930D01*
G03X656203Y93608I-2678J0D01*
G01X655137D01*
G02X654037Y94708I0J1100D01*
G01X708661Y14961D02*
Y16412D01*
G03X708005Y17068I-656J0D01*
G01X705772D01*
X703922Y17461D01*
X702473Y18402D01*
X700414Y21571D01*
X700413D01*
X696166Y41552D01*
Y41553D01*
X693849Y45119D01*
X692881Y45324D01*
X691982Y46708D01*
X692188Y47676D01*
X691289Y49060D01*
X690321Y49265D01*
X689422Y50649D01*
X689628Y51617D01*
X688729Y53001D01*
X687760Y53206D01*
X686861Y54590D01*
X687067Y55558D01*
X683608Y60883D01*
X665026Y73415D01*
X654696Y76927D01*
X653864Y79087D01*
X653571Y79849D01*
X653514Y79999D01*
X653455Y80151D01*
X653143Y80960D01*
X653301Y81806D01*
X653368Y82167D01*
X653627Y83559D01*
X657123Y88141D01*
X657581Y90102D01*
Y90930D01*
G03X656203Y92308I-1378J0D01*
G01X655137D01*
G03X654037Y91208I0J-1100D01*
G01X715748Y15748D02*
Y14298D01*
G02X715093Y13643I-655J0D01*
G01X713974D01*
G02X712854Y14763I0J1120D01*
G01Y52121D01*
X712311Y54677D01*
X711299Y56236D01*
X708633Y58037D01*
X698845Y59936D01*
X679051Y73284D01*
X664938Y79242D01*
X664266Y80278D01*
X663788Y82551D01*
X664036Y83712D01*
X664118Y84098D01*
X666666Y88660D01*
Y91184D01*
G03X664411Y93439I-2255J0D01*
G01X663147D01*
G02X662047Y94539I0J1100D01*
G01X715748Y10237D02*
Y11687D01*
G03X715092Y12343I-656J0D01*
G01X713974D01*
G02X711554Y14763I0J2420D01*
G01Y51984D01*
X711089Y54171D01*
X710352Y55306D01*
X708125Y56811D01*
X698337Y58709D01*
X691220Y63509D01*
X690248Y63320D01*
X688880Y64243D01*
X688691Y65214D01*
X687323Y66137D01*
X686351Y65948D01*
X684983Y66871D01*
X684794Y67842D01*
X683426Y68765D01*
X682454Y68576D01*
X681086Y69499D01*
X680897Y70470D01*
X680213Y70932D01*
X678428Y72135D01*
X664064Y78199D01*
X663043Y79773D01*
X662459Y82552D01*
X662886Y84561D01*
X665366Y88999D01*
Y91184D01*
G03X664411Y92139I-955J0D01*
G01X663147D01*
G03X662047Y91039I0J-1100D01*
G01X722834Y20473D02*
Y19023D01*
G02X722178Y18367I-656J0D01*
G01X720860D01*
G02X719941Y19286I0J919D01*
G01Y49448D01*
X718905Y52784D01*
X714912Y58701D01*
X709958Y62044D01*
X703087Y63381D01*
X682385Y77344D01*
X675088Y88339D01*
Y90610D01*
G03X672293Y93405I-2795J0D01*
G01X671246D01*
G02X670146Y94505I0J1100D01*
G01X722834Y14961D02*
Y16411D01*
G03X722178Y17067I-656J0D01*
G01X720860D01*
G02X718641Y19286I0J2219D01*
G01Y49250D01*
X717720Y52216D01*
X717719Y52215D01*
X713975Y57764D01*
X712846Y58526D01*
X709450Y60818D01*
X702579Y62155D01*
X697734Y65423D01*
X696762Y65234D01*
X695394Y66157D01*
X695206Y67128D01*
X693838Y68051D01*
X692866Y67862D01*
X691498Y68784D01*
X691309Y69756D01*
X689941Y70679D01*
X688969Y70490D01*
X687601Y71412D01*
X687413Y72384D01*
X681444Y76410D01*
X673788Y87946D01*
Y90610D01*
G03X672293Y92105I-1495J0D01*
G01X671246D01*
G03X670146Y91005I0J-1100D01*
G01X729921Y15748D02*
Y14298D01*
G02X729266Y13643I-655J0D01*
G01X728147D01*
G02X727027Y14763I0J1120D01*
G01Y53172D01*
X726864Y54015D01*
X726674Y54993D01*
X724511Y58209D01*
X709718Y67812D01*
X701975Y69692D01*
X688267Y79151D01*
X687349Y80586D01*
X686980Y81854D01*
X686491Y83534D01*
X683161Y87921D01*
Y90775D01*
G03X680540Y93396I-2621J0D01*
G01X679325D01*
G02X678225Y94496I0J1100D01*
G01X729921Y10237D02*
Y11687D01*
G03X729265Y12343I-656J0D01*
G01X728147D01*
G02X725727Y14763I0J2420D01*
G01Y53047D01*
X725448Y54486D01*
X724357Y56106D01*
Y56107D01*
X723580Y57263D01*
X709196Y66600D01*
X701435Y68485D01*
X700077Y69422D01*
X699103Y69243D01*
X697745Y70180D01*
X697566Y71154D01*
X696208Y72091D01*
X695234Y71912D01*
X693876Y72850D01*
X693697Y73823D01*
X692339Y74760D01*
X691365Y74582D01*
X690007Y75519D01*
X689829Y76492D01*
X687312Y78229D01*
X686153Y80043D01*
X685309Y82941D01*
X681861Y87483D01*
Y90775D01*
G03X680540Y92096I-1321J0D01*
G01X679325D01*
G03X678225Y90996I0J-1100D01*
G01X737007Y20473D02*
Y19023D01*
G02X736351Y18367I-656J0D01*
G01X735033D01*
G02X734114Y19286I0J919D01*
G01Y47566D01*
X733060Y52989D01*
X731650Y55079D01*
X730388Y56950D01*
X727377Y61415D01*
X710949Y72495D01*
X701977Y74240D01*
X699127Y76162D01*
X694313Y80976D01*
Y84375D01*
X691147Y87541D01*
Y91035D01*
G03X688788Y93394I-2359J0D01*
G01X687379D01*
G02X686279Y94494I0J1100D01*
G01X737007Y14961D02*
Y16411D01*
G03X736351Y17067I-656J0D01*
G01X735033D01*
G02X732814Y19286I0J2219D01*
G01Y47440D01*
X731834Y52481D01*
X729310Y56223D01*
X726440Y60478D01*
X725072Y61401D01*
X724100Y61212D01*
X722732Y62134D01*
X722543Y63106D01*
X721175Y64029D01*
X720203Y63840D01*
X718835Y64762D01*
X718647Y65734D01*
X717279Y66657D01*
X716307Y66468D01*
X714939Y67390D01*
X714751Y68362D01*
X710441Y71269D01*
X701469Y73014D01*
X698296Y75154D01*
X693013Y80437D01*
Y83836D01*
X689847Y87002D01*
Y91035D01*
G03X688788Y92094I-1059J0D01*
G01X687379D01*
G03X686279Y90994I0J-1100D01*
G01X744094Y15748D02*
Y14298D01*
G02X743439Y13643I-655J0D01*
G01X742320D01*
G02X741201Y14762I0J1119D01*
G01Y51716D01*
X740534Y54855D01*
X736447Y61154D01*
X714854Y75718D01*
X702084Y78432D01*
X701678Y78690D01*
X701626Y78723D01*
X701619Y78728D01*
X701614Y78731D01*
X701613Y78732D01*
X701157Y79029D01*
X701065Y79088D01*
X700865Y79218D01*
Y79217D01*
X700583Y79653D01*
X700298Y80091D01*
Y80090D01*
X699870Y82104D01*
X699823Y82324D01*
X699074Y85848D01*
Y90974D01*
G03X696690Y93358I-2384J0D01*
G01X695465D01*
G02X694365Y94458I0J1100D01*
G01X744094Y10237D02*
Y11687D01*
G03X743438Y12343I-656J0D01*
G01X742320D01*
G02X739901Y14762I0J2419D01*
G01Y51579D01*
X739312Y54349D01*
X735500Y60224D01*
X731144Y63162D01*
X730172Y62973D01*
X728804Y63896D01*
X728615Y64868D01*
X727247Y65791D01*
X726275Y65602D01*
X724907Y66524D01*
X724718Y67496D01*
X723350Y68419D01*
X722378Y68230D01*
X721010Y69152D01*
X720821Y70124D01*
X714336Y74498D01*
X701560Y77214D01*
X700916Y77633D01*
X700903Y77641D01*
X700790Y77715D01*
X700789D01*
X699925Y78277D01*
X699076Y79584D01*
X697774Y85711D01*
Y90974D01*
G03X696690Y92058I-1084J0D01*
G01X695465D01*
G03X694365Y90958I0J-1100D01*
G01X751181Y20473D02*
Y19023D01*
G02X750525Y18367I-656J0D01*
G01X749207D01*
G02X748288Y19286I0J919D01*
G01Y46977D01*
X746857Y53719D01*
X740482Y63531D01*
X709206Y84630D01*
X707585Y87126D01*
X707256Y88671D01*
Y90860D01*
G03X704706Y93410I-2550J0D01*
G01X703491D01*
G02X702391Y94510I0J1100D01*
G01X751181Y14961D02*
Y16411D01*
G03X750525Y17067I-656J0D01*
G01X749207D01*
G02X746988Y19286I0J2219D01*
G01Y46840D01*
X745635Y53213D01*
X739535Y62600D01*
X731810Y67811D01*
X730838Y67622D01*
X729470Y68545D01*
X729282Y69517D01*
X727914Y70440D01*
X726942Y70251D01*
X725575Y71174D01*
X725386Y72145D01*
X724018Y73068D01*
X723046Y72879D01*
X721679Y73802D01*
X721490Y74773D01*
X708259Y83699D01*
X706363Y86619D01*
X706149Y87627D01*
X705956Y88533D01*
Y90860D01*
G03X704706Y92110I-1250J0D01*
G01X703491D01*
G03X702391Y91010I0J-1100D01*
G01X758267Y15748D02*
Y14298D01*
G02X757612Y13643I-655J0D01*
G01X756493D01*
G02X755374Y14762I0J1119D01*
G01Y51569D01*
X754829Y54137D01*
X747813Y64942D01*
X729434Y78837D01*
X729433D01*
X721635Y84734D01*
X716284Y92973D01*
X715481Y93776D01*
Y93777D01*
X714892Y94363D01*
G03X712635Y95299I-2259J-2257D01*
G01X711478D01*
G02X710378Y96399I0J1100D01*
G01X758267Y10237D02*
Y11687D01*
G03X757611Y12343I-656J0D01*
G01X756493D01*
G02X754074Y14762I0J2419D01*
G01Y51432D01*
X753840Y52533D01*
X753607Y53631D01*
X751917Y56232D01*
X750773Y57993D01*
X750227Y58835D01*
X749084Y60595D01*
X747966Y62319D01*
X746846Y64042D01*
X738579Y70292D01*
X737599Y70156D01*
X736283Y71151D01*
X736147Y72131D01*
X734831Y73126D01*
X733850Y72990D01*
X732534Y73985D01*
X732398Y74965D01*
X731082Y75960D01*
X730101Y75824D01*
X728785Y76819D01*
X728649Y77800D01*
X720668Y83834D01*
X715268Y92150D01*
X714562Y92856D01*
X713973Y93443D01*
G03X712634Y93999I-1340J-1337D01*
G01X711478D01*
G03X710378Y92899I0J-1100D01*
G54D13*
G01X765764Y326844D02*
X790381D01*
X805254Y311971D01*
Y263886D01*
X388189Y44095D03*
X374016D03*
X359843D03*
X345670D03*
X388189Y38583D03*
X374016D03*
X359843D03*
X345670D03*
X388189Y5906D03*
X374016D03*
X359843D03*
X345670D03*
X381103Y48819D03*
X366929D03*
X352756D03*
X338583D03*
X381103Y43307D03*
X366929D03*
X352756D03*
X338583D03*
Y29134D03*
X444882Y44095D03*
X430709D03*
X416536D03*
X402363D03*
X444882Y38583D03*
X430709D03*
X416536D03*
X402363D03*
X444882Y5906D03*
X430709D03*
X416536D03*
X402363D03*
X437796Y48819D03*
X423622D03*
X409449D03*
X395276D03*
X437796Y43307D03*
X423622D03*
X409449D03*
X395276D03*
X501575Y44095D03*
X487402D03*
X473229D03*
X459055D03*
X501575Y38583D03*
X487402D03*
X473229D03*
X459055D03*
X501575Y5906D03*
X487402D03*
X473229D03*
X459055D03*
X508662Y48819D03*
X494489D03*
X480315D03*
X466142D03*
X451969D03*
X508662Y43307D03*
X494489D03*
X480315D03*
X466142D03*
X451969D03*
X572441Y44095D03*
X558268D03*
X544095D03*
X529922D03*
X515748D03*
X572441Y38583D03*
X558268D03*
X544095D03*
X529922D03*
X515748D03*
X572441Y5906D03*
X558268D03*
X544095D03*
X529922D03*
X515748D03*
X565355Y48819D03*
X551181D03*
X537008D03*
X522835D03*
X565355Y43307D03*
X551181D03*
X537008D03*
X522835D03*
X586614Y44095D03*
Y38583D03*
Y5906D03*
X579528Y48819D03*
Y43307D03*
X758267Y15748D03*
X744094D03*
X729921D03*
X715748D03*
X758267Y10237D03*
X744094D03*
X729921D03*
X715748D03*
X758267Y5906D03*
X744094D03*
X729921D03*
X715748D03*
X751181Y20473D03*
X737007D03*
X722834D03*
X708661D03*
X751181Y14961D03*
X737007D03*
X722834D03*
X708661D03*
G54D14*
X389000Y236100D03*
X401575Y236221D03*
X405512D03*
X417322D03*
X409449Y204725D03*
Y200788D03*
X413386Y208662D03*
Y204725D03*
X417323D03*
Y200788D03*
X421260Y208662D03*
Y204725D03*
X425197D03*
Y200788D03*
X429134Y208662D03*
Y204725D03*
X433071D03*
Y200788D03*
X437008Y208662D03*
Y204725D03*
X440945D03*
Y200788D03*
X444882Y208662D03*
Y204725D03*
X448819D03*
Y200788D03*
X393701Y204725D03*
Y200788D03*
X397638Y208662D03*
Y204725D03*
X401575D03*
Y200788D03*
X405512Y208662D03*
Y204725D03*
X425197Y291339D03*
X433071Y295276D03*
Y299213D03*
Y291339D03*
X437007Y287402D03*
X429134Y291340D03*
X417323Y251969D03*
X413386Y248032D03*
X405512D03*
X421260Y251969D03*
X405512Y244095D03*
X401575D03*
X413386D03*
X417323Y248032D03*
X401575Y240158D03*
X405512D03*
X433070Y287402D03*
X413387Y240158D03*
X421260Y248032D03*
X417323Y244095D03*
X413386Y251969D03*
X401575Y248032D03*
X425197Y303150D03*
X421260Y326772D03*
X421259Y322835D03*
X421260Y318898D03*
Y314961D03*
X417322Y322835D03*
X413386Y314962D03*
X421260Y307088D03*
X433071Y303150D03*
X456693Y208662D03*
Y204725D03*
X460630D03*
Y200788D03*
X464567Y208662D03*
Y204725D03*
X468504D03*
Y200788D03*
X472441Y208662D03*
Y204725D03*
X476378D03*
Y200788D03*
X480315Y208662D03*
Y204725D03*
X484252D03*
Y200788D03*
X488189Y208662D03*
Y204725D03*
X456694Y295276D03*
X507874Y255906D03*
X511811D03*
Y259843D03*
X507874Y267717D03*
X511811D03*
X507874Y240158D03*
X511811D03*
Y244095D03*
Y271654D03*
X507874Y248032D03*
X511811D03*
Y251969D03*
X507874Y275591D03*
X511811D03*
Y279528D03*
X507874Y283465D03*
X511811D03*
Y287402D03*
X460630Y291339D03*
X468504Y303151D03*
X460630Y303150D03*
X464567Y303151D03*
Y307088D03*
X468505D03*
X464567Y311025D03*
Y318898D03*
X470473Y327204D03*
X515748Y259843D03*
Y244095D03*
Y271654D03*
Y251969D03*
Y279528D03*
Y287402D03*
X682675Y132281D03*
X688974D03*
G54D15*
X404528Y412795D03*
X413386D03*
X407480Y422244D03*
X416339D03*
X407480Y407284D03*
X416339D03*
X404528Y427756D03*
X413386D03*
G54D16*
G01X359969Y124510D02*
X360400Y124079D01*
Y95900D01*
X304800Y40300D01*
X229418D01*
X178816Y90902D01*
X132987D01*
X120900Y102989D01*
Y134760D01*
X98784Y156876D01*
Y225960D01*
X78814Y245930D01*
X41819D01*
X37469Y250280D01*
G01X102300Y329100D02*
X100300D01*
X97700Y331700D01*
Y356500D01*
X92900Y361300D01*
Y371321D01*
X85795Y378426D01*
G01X448500Y424000D02*
X450500Y426000D01*
X453031D01*
X482281Y455250D01*
X495056D01*
X499941Y460135D01*
X548708D01*
X565763Y477190D01*
X643320D01*
X672215Y448295D01*
X719295D01*
X726000Y455000D01*
X732500D01*
X737780Y449720D01*
Y444780D01*
X743480Y439080D01*
G01X588400Y469450D02*
X561460D01*
X549945Y457935D01*
X500853D01*
X495968Y453050D01*
X484081D01*
X454531Y423500D01*
X452500D01*
G01X574250Y466900D02*
X591150D01*
X599240Y474990D01*
X640170D01*
X669065Y446095D01*
X701435D01*
X706120Y441410D01*
G01X581250Y480550D02*
X584430Y483730D01*
X641390D01*
X670710Y454410D01*
X671640D01*
G01X697149Y219742D02*
X696247Y220644D01*
Y228508D01*
X700233Y232494D01*
Y275337D01*
X752723Y327827D01*
Y380489D01*
X745312Y387900D01*
X717242D01*
X713109Y383767D01*
X704633D01*
X700200Y388200D01*
G01X692949Y219742D02*
X694047Y220840D01*
Y229536D01*
X697933Y233422D01*
Y276149D01*
X750523Y328739D01*
Y379577D01*
X744400Y385700D01*
X718154D01*
X714021Y381567D01*
X703433D01*
X700200Y384800D01*
G54D17*
G01X198557Y153196D02*
X192556D01*
X185877Y159875D01*
Y242539D01*
X158067Y270349D01*
Y378857D01*
G01X343100Y281300D02*
X342700Y281700D01*
Y298700D01*
X346500Y302500D01*
G01X344000Y316000D02*
Y313400D01*
X346500Y310900D01*
Y302500D01*
G01X635000Y427784D02*
X643716Y436500D01*
X669000D01*
X672000Y433500D01*
X691500D01*
X693500Y435500D01*
X720500D01*
X729870Y444870D01*
Y451300D01*
G54D18*
G01X412033Y198982D02*
Y196770D01*
X411454Y194041D01*
X405441Y184782D01*
X405191Y183607D01*
X405769Y182718D01*
X405519Y181544D01*
X404630Y180966D01*
X404348Y179633D01*
X403405Y178288D01*
X403196Y177103D01*
Y171485D01*
X407092Y149371D01*
X398001Y106604D01*
X364526Y55063D01*
X363986Y52522D01*
Y47524D01*
G03X364847Y46663I861J0D01*
G01X366223D01*
G03X366929Y47369I0J706D01*
G01Y48819D01*
G01X410833Y198982D02*
Y196896D01*
X410326Y194508D01*
X404312Y185248D01*
X403224Y180122D01*
X402269Y178759D01*
X402096Y177772D01*
X401996Y177209D01*
Y171380D01*
X405869Y149392D01*
X401372Y128234D01*
X396873Y107071D01*
X363398Y55530D01*
X362786Y52649D01*
Y47524D01*
G03X364847Y45463I2061J0D01*
G01X366223D01*
G02X366929Y44757I0J-706D01*
G01Y43307D01*
G01X415953Y198913D02*
Y195416D01*
X415132Y191551D01*
X411788Y186402D01*
X411538Y185227D01*
X412116Y184338D01*
X411866Y183164D01*
X410977Y182586D01*
X410374Y179754D01*
X410355Y179644D01*
X409405Y178288D01*
X409196Y177103D01*
Y171261D01*
X408380Y166630D01*
X408378Y166627D01*
X411715Y150927D01*
X401645Y103552D01*
X372518Y58702D01*
X371072Y51899D01*
Y42801D01*
G03X371934Y41939I862J0D01*
G01X373310D01*
G03X374016Y42645I0J706D01*
G01Y44095D01*
G01X414753Y198913D02*
Y195543D01*
X414004Y192018D01*
X410660Y186869D01*
X409230Y180144D01*
X409227Y180125D01*
X408824Y179551D01*
X408269Y178758D01*
X407996Y177209D01*
Y171366D01*
X407158Y166618D01*
X407182Y166481D01*
X410488Y150927D01*
X400517Y104019D01*
X371390Y59169D01*
X369872Y52026D01*
Y42801D01*
G03X371934Y40739I2062J0D01*
G01X373310D01*
G02X374016Y40033I0J-706D01*
G01Y38583D01*
G01X419907Y198982D02*
Y196462D01*
X417803Y186567D01*
X418380Y185677D01*
X418131Y184504D01*
X417241Y183926D01*
X416517Y180519D01*
X416366Y179662D01*
X415405Y178288D01*
X415196Y177103D01*
Y171261D01*
X414106Y165076D01*
X414547Y162584D01*
X414692Y161755D01*
X415277Y158437D01*
X416488Y151568D01*
X410890Y125228D01*
X405295Y98898D01*
X379725Y59526D01*
X378160Y52159D01*
Y47524D01*
G03X379021Y46663I861J0D01*
G01X380397D01*
G03X381103Y47369I0J706D01*
G01Y48819D01*
G01X418707Y198982D02*
Y196589D01*
X415339Y180752D01*
X415230Y180132D01*
X414269Y178758D01*
X413996Y177209D01*
Y171366D01*
X412887Y165076D01*
X413217Y163206D01*
X413510Y161547D01*
X414095Y158229D01*
X415265Y151589D01*
X404167Y99365D01*
X378597Y59993D01*
X376960Y52286D01*
Y47524D01*
G03X379021Y45463I2061J0D01*
G01X380397D01*
G02X381103Y44757I0J-706D01*
G01Y43307D01*
G01X423827Y198913D02*
Y194093D01*
X424626Y190338D01*
X424376Y189163D01*
X424954Y188274D01*
X424704Y187100D01*
X423815Y186522D01*
X422358Y179672D01*
X422353Y179645D01*
X422345Y179633D01*
X421405Y178288D01*
X421196Y177103D01*
Y171261D01*
X419726Y162921D01*
X421742Y153428D01*
X408967Y93329D01*
X387263Y59910D01*
X385246Y50417D01*
Y42800D01*
G03X386107Y41939I861J0D01*
G01X387483D01*
G03X388189Y42645I0J706D01*
G01Y44095D01*
G01X422627Y198913D02*
Y193966D01*
X423399Y190338D01*
X421227Y180130D01*
Y180129D01*
X421219Y180117D01*
X421218D01*
X421204Y180096D01*
X421201Y180093D01*
X421197Y180086D01*
X421189Y180074D01*
X420269Y178759D01*
X419996Y177209D01*
Y171366D01*
X418503Y162898D01*
X420515Y153428D01*
X407839Y93796D01*
X386135Y60377D01*
X384046Y50544D01*
Y42800D01*
G03X386107Y40739I2061J0D01*
G01X387483D01*
G02X388189Y40033I0J-706D01*
G01Y38583D01*
G01X338583Y48819D02*
Y47369D01*
G02X337877Y46663I-706J0D01*
G01X336501D01*
G02X335500Y47664I0J1001D01*
G01Y51136D01*
X336221Y54528D01*
X338532Y58086D01*
X350222Y65677D01*
X383933Y117588D01*
X391056Y151095D01*
X388785Y161765D01*
X386593Y165140D01*
X386592D01*
X379670Y169986D01*
X379337Y170461D01*
X379196Y171261D01*
Y177103D01*
X379405Y178288D01*
X380202Y179426D01*
X381634Y180430D01*
X386291Y188940D01*
X389970Y191328D01*
X391007Y191107D01*
X392014Y191760D01*
X392235Y192798D01*
X394147Y194039D01*
X396070Y197004D01*
X396279Y197986D01*
Y199348D01*
G01X338583Y43307D02*
Y44757D01*
G03X337877Y45463I-706J0D01*
G01X336501D01*
G02X334300Y47664I0J2201D01*
G01Y51263D01*
X335093Y54995D01*
X337664Y58954D01*
X349354Y66545D01*
X382805Y118055D01*
X389829Y151095D01*
X387657Y161297D01*
X385711Y164293D01*
X385709D01*
X378808Y169123D01*
X378201Y169990D01*
X377996Y171156D01*
Y177209D01*
X378269Y178758D01*
X379339Y180288D01*
X380714Y181251D01*
X385383Y189782D01*
X393279Y194907D01*
X394942Y197471D01*
X395079Y198113D01*
Y199348D01*
G01X400205Y198913D02*
Y197285D01*
X399942Y196047D01*
X397529Y192330D01*
X393358Y188159D01*
X392705Y187152D01*
X392926Y186115D01*
X392272Y185108D01*
X391235Y184888D01*
X389077Y181560D01*
X386421Y179701D01*
X386193Y179413D01*
X385405Y178288D01*
X385196Y177103D01*
Y171261D01*
X385290Y170730D01*
X385939Y169802D01*
X388247Y168185D01*
X391663Y162927D01*
X394566Y149279D01*
X387283Y115014D01*
X352705Y61769D01*
X347478Y58375D01*
X342984Y51457D01*
X342726Y50242D01*
Y42801D01*
G03X343588Y41939I862J0D01*
G01X344964D01*
G03X345670Y42645I0J706D01*
G01Y44095D01*
G01X399005Y198913D02*
Y197412D01*
X398814Y196515D01*
X396590Y193090D01*
X392419Y188919D01*
X388195Y182409D01*
X385590Y180584D01*
X385230Y180132D01*
X384269Y178758D01*
X383996Y177209D01*
Y171155D01*
X384154Y170259D01*
X385076Y168940D01*
X387367Y167335D01*
X387537Y167074D01*
X390535Y162459D01*
X393339Y149279D01*
X386155Y115481D01*
X351837Y62637D01*
X346610Y59243D01*
X341856Y51924D01*
X341526Y50369D01*
Y42801D01*
G03X343588Y40739I2062J0D01*
G01X344964D01*
G02X345670Y40033I0J-706D01*
G01Y38583D01*
G01X404159Y198982D02*
Y196777D01*
X394231Y181488D01*
X394230Y181487D01*
X394451Y180449D01*
X393797Y179443D01*
X392760Y179222D01*
X391196Y176817D01*
Y171464D01*
X391432Y170128D01*
X395079Y164917D01*
X395080Y164916D01*
X398443Y149087D01*
X390669Y112509D01*
X355687Y58643D01*
X355472Y58503D01*
Y58504D01*
X351910Y56189D01*
X350016Y53274D01*
X349813Y52320D01*
Y47524D01*
G03X350674Y46663I861J0D01*
G01X352050D01*
G03X352756Y47369I0J706D01*
G01Y48819D01*
G01X402959Y198982D02*
Y197133D01*
X390968Y178675D01*
X390971Y178674D01*
X389996Y177173D01*
Y171358D01*
X390020Y171219D01*
X390296Y169657D01*
X393956Y164428D01*
X397216Y149087D01*
X393378Y131030D01*
X393377D01*
X389541Y112976D01*
X354819Y59511D01*
X351042Y57057D01*
X348888Y53741D01*
X348613Y52447D01*
Y47524D01*
G03X350674Y45463I2061J0D01*
G01X352050D01*
G02X352756Y44757I0J-706D01*
G01Y43307D01*
G01X408079Y198913D02*
Y197126D01*
X407729Y195481D01*
X406779Y194019D01*
X407000Y192982D01*
X406347Y191975D01*
X405309Y191754D01*
X398221Y180834D01*
X397799Y178851D01*
X397405Y178288D01*
X397196Y177103D01*
Y171687D01*
X397391Y170580D01*
X399063Y168195D01*
X402453Y148971D01*
X402569Y148303D01*
X398215Y127818D01*
X393924Y107626D01*
X356899Y50616D01*
Y42801D01*
G03X357761Y41939I862J0D01*
G01X359137D01*
G03X359843Y42645I0J706D01*
G01Y44095D01*
G01X406879Y198913D02*
Y197253D01*
X406601Y195949D01*
X397093Y181301D01*
X396676Y179340D01*
X396269Y178758D01*
X395996Y177209D01*
Y171582D01*
X396014Y171479D01*
X396111Y170926D01*
X396160Y170649D01*
X396255Y170109D01*
X397927Y167724D01*
X401270Y148764D01*
X401347Y148326D01*
X397041Y128067D01*
X394918Y118079D01*
X392796Y108093D01*
X374405Y79775D01*
X355699Y50972D01*
Y42801D01*
G03X357761Y40739I2062J0D01*
G01X359137D01*
G02X359843Y40033I0J-706D01*
G01Y38583D01*
G01X427781Y198982D02*
Y194983D01*
X428324Y192426D01*
X429213Y191849D01*
X429463Y190675D01*
X428885Y189785D01*
X428886D01*
X429206Y188276D01*
X427196Y176890D01*
Y170826D01*
X425234Y159691D01*
X425938Y156378D01*
X426744Y152585D01*
X413146Y88608D01*
X394027Y59167D01*
X392333Y51199D01*
Y47524D01*
G03X393194Y46663I861J0D01*
G01X394570D01*
G03X395276Y47369I0J706D01*
G01Y48819D01*
G01X426581Y198982D02*
Y194856D01*
X427983Y188255D01*
X425996Y176996D01*
Y170931D01*
X424011Y159670D01*
X425517Y152585D01*
X412018Y89075D01*
X392899Y59634D01*
X391133Y51326D01*
Y47524D01*
G03X393194Y45463I2061J0D01*
G01X394570D01*
G02X395276Y44757I0J-706D01*
G01Y43307D01*
G01X431701Y198913D02*
Y195199D01*
X433057Y188821D01*
X433947Y188243D01*
X434196Y187069D01*
X433618Y186180D01*
X434252Y183200D01*
X433196Y177208D01*
Y171391D01*
X430906Y158479D01*
X431931Y153650D01*
X416426Y80682D01*
X400110Y55559D01*
X399419Y52308D01*
Y42801D01*
G03X400281Y41939I862J0D01*
G01X401657D01*
G03X402363Y42645I0J706D01*
G01Y44095D01*
G01X430501Y198913D02*
Y195072D01*
X433029Y183179D01*
X432512Y180246D01*
Y180245D01*
X431996Y177313D01*
Y171497D01*
X429683Y158458D01*
X430704Y153650D01*
X423001Y117398D01*
X415298Y81149D01*
X399103Y56212D01*
X398982Y56026D01*
X398219Y52435D01*
Y42801D01*
G03X400281Y40739I2062J0D01*
G01X401657D01*
G02X402363Y40033I0J-706D01*
G01Y38583D01*
G01X435655Y198982D02*
Y195542D01*
X437957Y184719D01*
X438846Y184141D01*
X439096Y182967D01*
X438518Y182078D01*
X438844Y180548D01*
Y180547D01*
X439195Y178895D01*
X439196Y178418D01*
Y171839D01*
X436672Y157528D01*
X436727Y157269D01*
X437103Y155500D01*
X421091Y80154D01*
X408069Y60104D01*
X406506Y52752D01*
Y47524D01*
G03X407367Y46663I861J0D01*
G01X408743D01*
G03X409449Y47369I0J706D01*
G01Y48819D01*
G01X434455Y198982D02*
Y195415D01*
X437995Y178767D01*
X437996Y178416D01*
Y171945D01*
X435449Y157507D01*
X435876Y155500D01*
X419963Y80621D01*
X406941Y60571D01*
X405306Y52879D01*
Y47524D01*
G03X407367Y45463I2061J0D01*
G01X408743D01*
G02X409449Y44757I0J-706D01*
G01Y43307D01*
G01X439575Y198913D02*
Y195337D01*
X441645Y185604D01*
X444024Y181941D01*
X444193Y181144D01*
X445083Y180566D01*
X445332Y179393D01*
X444755Y178504D01*
X445196Y176404D01*
Y171553D01*
X444879Y169760D01*
X444690Y169490D01*
X444179Y168758D01*
X444161Y168672D01*
X444160D01*
X424987Y78441D01*
X416305Y65074D01*
X414949Y58695D01*
X413592Y52314D01*
Y42801D01*
G03X414454Y41939I862J0D01*
G01X415830D01*
G03X416536Y42645I0J706D01*
G01Y44095D01*
G01X438375Y198913D02*
Y195210D01*
X440517Y185136D01*
X442896Y181474D01*
X443996Y176270D01*
Y171659D01*
X443743Y170231D01*
X443055Y169246D01*
X423859Y78908D01*
X415177Y65541D01*
X412392Y52441D01*
Y42801D01*
G03X414454Y40739I2062J0D01*
G01X415830D01*
G02X416536Y40033I0J-706D01*
G01Y38583D01*
G01X443529Y198982D02*
Y195203D01*
X444927Y188625D01*
X445581Y187619D01*
X446618Y187398D01*
X447272Y186392D01*
X447052Y185355D01*
X450102Y180658D01*
X450737Y179749D01*
X451196Y177143D01*
Y171358D01*
X450969Y170065D01*
X447429Y164952D01*
X428585Y76271D01*
X423003Y67675D01*
X420679Y56746D01*
Y47524D01*
G03X421540Y46663I861J0D01*
G01X422916D01*
G03X423622Y47369I0J706D01*
G01Y48819D01*
G01X442329Y198982D02*
Y195076D01*
X443799Y188158D01*
X449106Y179986D01*
X449601Y179279D01*
X449996Y177038D01*
Y171463D01*
X449832Y170532D01*
X446305Y165437D01*
X427457Y76738D01*
X424787Y72626D01*
X421875Y68142D01*
X419479Y56873D01*
Y47524D01*
G03X421540Y45463I2061J0D01*
G01X422916D01*
G02X423622Y44757I0J-706D01*
G01Y43307D01*
G01X447449Y198913D02*
Y195606D01*
X447989Y193064D01*
X451819Y187166D01*
X452856Y186946D01*
X453510Y185939D01*
X453289Y184902D01*
X456711Y179633D01*
X456861Y178883D01*
X457196Y176981D01*
Y171387D01*
X456982Y170173D01*
X451147Y161845D01*
X427765Y51841D01*
Y42801D01*
G03X428627Y41939I862J0D01*
G01X430003D01*
G03X430709Y42645I0J706D01*
G01Y44095D01*
G01X446249Y198913D02*
Y195479D01*
X446861Y192597D01*
X455579Y179172D01*
X455681Y178661D01*
X455996Y176875D01*
Y171492D01*
X455846Y170644D01*
X450023Y162334D01*
X426565Y51968D01*
Y42801D01*
G03X428627Y40739I2062J0D01*
G01X430003D01*
G02X430709Y40033I0J-706D01*
G01Y38583D01*
G01X451423Y198982D02*
Y196690D01*
X452077Y195684D01*
X453114Y195463D01*
X453768Y194457D01*
X453547Y193419D01*
Y193418D01*
X461871Y180606D01*
X462710Y179406D01*
X463196Y176648D01*
Y171720D01*
X462971Y170444D01*
X462569Y169871D01*
X457016Y161318D01*
X434853Y57084D01*
Y47524D01*
G03X435714Y46663I861J0D01*
G01X437090D01*
G03X437796Y47369I0J706D01*
G01Y48819D01*
G01X450223Y198982D02*
Y196333D01*
X460875Y179934D01*
X461574Y178936D01*
X461582Y178888D01*
X461784Y177741D01*
X461996Y176542D01*
Y171825D01*
X461940Y171513D01*
X461915Y171369D01*
X461835Y170915D01*
X461574Y170543D01*
X455888Y161785D01*
X433653Y57211D01*
Y47524D01*
G03X435714Y45463I2061J0D01*
G01X437090D01*
G02X437796Y44757I0J-706D01*
G01Y43307D01*
G01X459260Y198913D02*
Y197274D01*
X460844Y189825D01*
X463176Y186234D01*
X464213Y186013D01*
X464867Y185007D01*
X464646Y183969D01*
X466824Y180613D01*
Y180612D01*
X469196Y176959D01*
Y171713D01*
X462978Y160268D01*
X441939Y61186D01*
Y42800D01*
G03X442800Y41939I861J0D01*
G01X444176D01*
G03X444882Y42645I0J706D01*
G01Y44095D01*
G01X458060Y198913D02*
Y197147D01*
X459716Y189358D01*
X467996Y176603D01*
Y172018D01*
X461840Y160688D01*
X440739Y61312D01*
Y42800D01*
G03X442800Y40739I2061J0D01*
G01X444176D01*
G02X444882Y40033I0J-706D01*
G01Y38583D01*
G01X462014Y198982D02*
Y196837D01*
X462868Y192801D01*
X471074Y180168D01*
X471216Y179979D01*
X472257Y179250D01*
X473882Y176927D01*
X473881D01*
X473938Y176604D01*
X473996Y176279D01*
Y171816D01*
X473548Y171178D01*
X466438Y160225D01*
X447826Y72702D01*
Y47524D01*
G03X449887Y45463I2061J0D01*
G01X451263D01*
G02X451969Y44757I0J-706D01*
G01Y43307D01*
G01X545278Y315738D02*
X546288D01*
G03X546741Y315925I1J640D01*
G01X546742Y315926D01*
G03X546928Y316377I-454J451D01*
G01Y317307D01*
G02X547600Y318931I2296J1D01*
G02X549224Y319603I1623J-1624D01*
G01X554855D01*
X559771Y321134D01*
X564170Y327902D01*
Y327903D01*
X564998Y331798D01*
X564420Y332688D01*
X564669Y333861D01*
X565559Y334439D01*
X565808Y335613D01*
X565231Y336502D01*
X565480Y337676D01*
X566369Y338254D01*
X566860Y340562D01*
X561118Y367591D01*
X549296Y385801D01*
X537019Y393774D01*
X470754Y407858D01*
X446953Y402798D01*
X436762Y404965D01*
X420095Y401421D01*
X415138Y402476D01*
X414173Y403103D01*
X413178Y403748D01*
X412360Y405011D01*
X412047Y406485D01*
Y407026D01*
G02X413075Y409466I3408J1D01*
G01X413308Y409699D01*
X413547Y409939D01*
G02X413924Y410218I1130J-1133D01*
G01X414133Y410330D01*
X414225Y410379D01*
G03X414389Y410921I-188J353D01*
G01X413386Y412795D01*
G01X416339Y407284D02*
G02X415334Y409157I300947J162686D01*
G03X414792Y409321I-353J-188D01*
G01X414491Y409160D01*
G03X414397Y409090I189J-352D01*
G01X413918Y408611D01*
G03X413247Y407026I1537J-1585D01*
G01Y406612D01*
X413488Y405478D01*
X414047Y404616D01*
X415605Y403604D01*
X420095Y402648D01*
X436762Y406192D01*
X446953Y404025D01*
X470754Y409085D01*
X471003Y409033D01*
Y409032D01*
X537486Y394902D01*
X550164Y386669D01*
X562246Y368058D01*
X568087Y340562D01*
X565298Y327435D01*
X560542Y320116D01*
X555038Y318403D01*
X549224D01*
G03X548449Y318082I0J-1096D01*
G03X548128Y317307I775J-775D01*
G01Y316436D01*
G03X548333Y315943I698J1D01*
G01X548420Y315856D01*
G03X548703Y315738I284J282D01*
G01X549778D01*
G01X546627Y324049D02*
X547637D01*
G03X548090Y324236I1J640D01*
G01X548091Y324237D01*
G03X548277Y324688I-454J451D01*
G01Y325454D01*
G02X548891Y326938I2098J1D01*
G01X549160Y327207D01*
G02X551565Y328203I2405J-2406D01*
G01X553014D01*
X556635Y329126D01*
X559646Y331079D01*
X560045Y331693D01*
X562295Y342279D01*
X561470Y346158D01*
X560580Y346736D01*
X560330Y347910D01*
X560908Y348799D01*
X560658Y349973D01*
X559769Y350551D01*
X559519Y351725D01*
X560097Y352614D01*
X557742Y363685D01*
X545499Y382531D01*
X534900Y389417D01*
X468267Y403581D01*
X446964Y399052D01*
X439253Y400690D01*
X422337Y397093D01*
X416149Y398407D01*
X416146Y398408D01*
X416142Y398409D01*
X412300Y399225D01*
Y399226D01*
X408238Y400089D01*
X405018Y402180D01*
X403361Y404732D01*
G02X404689Y409938I5052J1484D01*
G02X405066Y410218I1132J-1130D01*
G01X405275Y410330D01*
X405367Y410379D01*
G03X405531Y410921I-188J353D01*
G01X404528Y412795D01*
G01X551127Y324049D02*
X550052D01*
G02X549769Y324167I1J400D01*
G01X549682Y324254D01*
G02X549477Y324747I493J494D01*
G01Y325454D01*
G02X549740Y326089I898J0D01*
G01X550009Y326358D01*
G02X551566Y327003I1557J-1557D01*
G01X553165D01*
X555120Y327501D01*
X557123Y328012D01*
X560514Y330210D01*
X561173Y331225D01*
X563522Y342279D01*
X558870Y364153D01*
X546367Y383399D01*
X535367Y390545D01*
X468267Y404808D01*
X446964Y400279D01*
X439253Y401917D01*
X422337Y398320D01*
X416399Y399582D01*
X416396Y399583D01*
X416392Y399584D01*
X408705Y401217D01*
X405886Y403048D01*
X404470Y405229D01*
G02X405539Y409090I3943J987D01*
G02X405633Y409160I283J-282D01*
G01X405934Y409321D01*
G02X406476Y409157I189J-352D01*
G03X407480Y407284I348383J185541D01*
G01X545193Y301280D02*
X546203D01*
G03X546656Y301467I1J640D01*
G01X546657Y301468D01*
G03X546843Y301919I-454J451D01*
G01Y302685D01*
G02X549898Y305740I3055J0D01*
G01X555722D01*
G03X556743Y306163I0J1444D01*
G01X562397Y309835D01*
X565094Y313987D01*
X564873Y315025D01*
X565527Y316031D01*
X566564Y316252D01*
X567218Y317258D01*
X566998Y318296D01*
X567652Y319302D01*
X568689Y319523D01*
X570281Y321974D01*
X574710Y342816D01*
X568687Y371149D01*
X555877Y390802D01*
X536256Y403544D01*
X475468Y416465D01*
X458209Y412797D01*
X431048Y418572D01*
X416277D01*
X416162Y418595D01*
X415445Y418739D01*
X414506Y418930D01*
X413305Y419709D01*
X412365Y421159D01*
G02X413928Y425181I3124J1101D01*
G01X414133Y425291D01*
X414134D01*
X414139Y425294D01*
X414142Y425296D01*
X414150Y425300D01*
X414157Y425304D01*
X414160Y425306D01*
X414226Y425340D01*
G03X414390Y425882I-188J353D01*
G01X413386Y427756D01*
G01X549693Y301280D02*
X548618D01*
G02X548335Y301398I1J400D01*
G01X548248Y301485D01*
G02X548043Y301978I493J494D01*
G01Y302685D01*
G02X549898Y304540I1855J0D01*
G01X555723D01*
G03X557487Y305214I0J2645D01*
G01X562064Y308187D01*
X563265Y308967D01*
X571409Y321507D01*
X575937Y342816D01*
X569815Y371617D01*
X556744Y391670D01*
X536723Y404672D01*
X475468Y417692D01*
X458209Y414024D01*
X431175Y419772D01*
X416398D01*
X414968Y420061D01*
X414174Y420577D01*
X413459Y421679D01*
G02X414492Y424121I2031J581D01*
G01X414700Y424232D01*
X414703Y424234D01*
X414707Y424236D01*
X414716Y424241D01*
X414786Y424278D01*
X414790Y424280D01*
X414793Y424282D01*
G02X415335Y424118I189J-352D01*
G01X416339Y422244D01*
G01X404528Y427756D02*
X405531Y425882D01*
G02X405367Y425340I-352J-189D01*
G01X405275Y425291D01*
X405066Y425179D01*
G03X404689Y424900I753J-1412D01*
G01X404450Y424660D01*
X404211Y424421D01*
G03X403280Y422173I2249J-2248D01*
G01Y421079D01*
X404240Y417807D01*
X407065Y415975D01*
X408698Y415627D01*
X409799Y415393D01*
X410237Y415300D01*
X427914D01*
X457854Y408935D01*
X473391Y412238D01*
X535974Y398935D01*
X552373Y388286D01*
X564384Y369790D01*
X570737Y339902D01*
X567629Y325276D01*
X565509Y322013D01*
X564472Y321792D01*
X563818Y320786D01*
X564039Y319748D01*
X563385Y318742D01*
X562348Y318521D01*
X561694Y317515D01*
X561915Y316477D01*
X561261Y315471D01*
X557070Y312749D01*
X549444D01*
G03X546871Y310176I0J-2573D01*
G01Y309410D01*
G02X546685Y308959I-640J0D01*
G01X546684Y308958D01*
G02X546231Y308771I-452J453D01*
G01X545221D01*
G01X549721D02*
X548646D01*
G02X548363Y308889I1J400D01*
G01X548276Y308976D01*
G02X548071Y309469I493J494D01*
G01Y310176D01*
G02X549444Y311549I1373J0D01*
G01X557426D01*
X562129Y314603D01*
X568757Y324809D01*
X571964Y339902D01*
X565512Y370257D01*
X553241Y389154D01*
X536441Y400063D01*
X473391Y413465D01*
X457854Y410162D01*
X428041Y416500D01*
X410364D01*
X407532Y417103D01*
X405267Y418572D01*
X404480Y421252D01*
Y422172D01*
G02X405060Y423572I1980J0D01*
G01X405539Y424051D01*
G02X405633Y424121I283J-282D01*
G01X405934Y424282D01*
G02X406476Y424118I189J-352D01*
G01X407480Y422244D01*
G01X514458Y237198D02*
Y217344D01*
X516457Y207935D01*
X528191Y189868D01*
X530740Y177871D01*
X505719Y60134D01*
Y47524D01*
G03X506580Y46663I861J0D01*
G01X507956D01*
G03X508662Y47369I0J706D01*
G01Y48819D01*
G01Y43307D02*
Y44757D01*
G03X507956Y45463I-706J0D01*
G01X506580D01*
G02X504519Y47524I0J2061D01*
G01Y60261D01*
X529513Y177871D01*
X527063Y189401D01*
X517555Y204040D01*
X516518Y204261D01*
X515864Y205267D01*
X516084Y206305D01*
X515329Y207468D01*
X513258Y217217D01*
Y237198D01*
G01X463214Y198982D02*
Y196963D01*
X463996Y193268D01*
X468167Y186847D01*
X469204Y186626D01*
X469858Y185620D01*
X469637Y184585D01*
X472059Y180857D01*
X472061Y180853D01*
X473120Y180112D01*
X475018Y177397D01*
X475196Y176385D01*
Y171437D01*
X474544Y170506D01*
X467566Y159758D01*
X449026Y72575D01*
Y47524D01*
G03X449887Y46663I861J0D01*
G01X451263D01*
G03X451969Y47369I0J706D01*
G01Y48819D01*
G01X459055Y44095D02*
Y42645D01*
G02X458349Y41939I-706J0D01*
G01X456973D01*
G02X456112Y42800I0J861D01*
G01Y83631D01*
X471431Y155705D01*
X472321Y156283D01*
X472570Y157457D01*
X471993Y158346D01*
X472242Y159520D01*
X477789Y168060D01*
X478942Y169707D01*
X479296Y171710D01*
Y176385D01*
X478865Y178833D01*
X467399Y196489D01*
X467134Y197732D01*
Y198913D01*
G01X459055Y38583D02*
Y40033D01*
G03X458349Y40739I-706J0D01*
G01X456973D01*
G02X454912Y42800I0J2061D01*
G01Y83758D01*
X471114Y159987D01*
X476661Y168527D01*
X477803Y170158D01*
X478096Y171816D01*
Y176279D01*
X477725Y178384D01*
X466271Y196021D01*
X465934Y197605D01*
Y198913D01*
G01X471088Y198621D02*
Y197227D01*
X481287Y181526D01*
X481823Y180239D01*
X483396Y176463D01*
Y171906D01*
X482867Y168902D01*
X481320Y165953D01*
X481324Y165951D01*
X481322Y165949D01*
X480397Y164525D01*
X480617Y163487D01*
X479964Y162481D01*
X478926Y162261D01*
X476313Y158238D01*
X461807Y90009D01*
X465743Y71496D01*
X463199Y59531D01*
Y47524D01*
G03X464060Y46663I861J0D01*
G01X465436D01*
G03X466142Y47369I0J706D01*
G01Y48819D01*
G01X469888Y198982D02*
Y196871D01*
X480220Y180964D01*
X482196Y176222D01*
Y172011D01*
X481717Y169294D01*
X480257Y166509D01*
X480255Y166510D01*
X480253Y166508D01*
X475185Y158705D01*
X460580Y90009D01*
X464516Y71496D01*
X461999Y59658D01*
Y47524D01*
G03X464060Y45463I2061J0D01*
G01X465436D01*
G02X466142Y44757I0J-706D01*
G01Y43307D01*
G01X473229Y44095D02*
Y42645D01*
G02X472523Y41939I-706J0D01*
G01X471147D01*
G02X470285Y42801I0J862D01*
G01Y63357D01*
X472363Y73135D01*
X469086Y88545D01*
X487496Y175107D01*
Y176193D01*
X486983Y179107D01*
X485805Y180784D01*
X484142Y183345D01*
X484362Y184383D01*
X483709Y185389D01*
X482671Y185610D01*
X475008Y197411D01*
Y198913D01*
G01X473229Y38583D02*
Y40033D01*
G03X472523Y40739I-706J0D01*
G01X471147D01*
G02X469085Y42801I0J2062D01*
G01Y63484D01*
X471136Y73135D01*
X467859Y88545D01*
X486296Y175234D01*
Y176088D01*
X485847Y178635D01*
X484809Y180112D01*
X473808Y197055D01*
Y198913D01*
G01X478962Y198982D02*
Y197794D01*
X479201Y196674D01*
X479720Y195873D01*
X481897Y194460D01*
X486038Y193580D01*
X486927Y194158D01*
X488101Y193908D01*
X488679Y193019D01*
X491783Y192359D01*
X493397Y191313D01*
X494120Y190200D01*
X494296Y189584D01*
X496605Y178638D01*
X494320Y167918D01*
X492598Y165266D01*
X475351Y84127D01*
X479648Y63912D01*
X477372Y53203D01*
Y47524D01*
G03X478233Y46663I861J0D01*
G01X479609D01*
G03X480315Y47369I0J706D01*
G01Y48819D01*
G01X477762Y198982D02*
Y197668D01*
X478072Y196207D01*
X478852Y195005D01*
X481430Y193332D01*
X491316Y191231D01*
X492529Y190444D01*
X493015Y189697D01*
X493128Y189303D01*
X493632Y186914D01*
X494253Y183970D01*
X495378Y178639D01*
X493192Y168386D01*
X491470Y165733D01*
X474124Y84127D01*
X478421Y63912D01*
X476172Y53330D01*
Y47524D01*
G03X478233Y45463I2061J0D01*
G01X479609D01*
G02X480315Y44757I0J-706D01*
G01Y43307D01*
G01X482890Y199260D02*
Y198735D01*
X483002Y198206D01*
X483187Y197921D01*
X483792Y197529D01*
X484868Y197299D01*
X488459Y198062D01*
X496656Y196321D01*
X496655Y196320D01*
X501342Y193488D01*
X501996Y192482D01*
X503033Y192261D01*
X503687Y191255D01*
X503466Y190217D01*
X505159Y187610D01*
X506532Y181160D01*
X503913Y168833D01*
X498695Y160799D01*
X482736Y85716D01*
X487265Y64409D01*
X484458Y51203D01*
Y42801D01*
G03X485320Y41939I862J0D01*
G01X486696D01*
G03X487402Y42645I0J706D01*
G01Y44095D01*
G01X481690Y199260D02*
Y198609D01*
X481874Y197739D01*
X482319Y197052D01*
X483325Y196401D01*
X484867Y196071D01*
X488459Y196835D01*
X496204Y195190D01*
X500485Y192603D01*
X504031Y187142D01*
X505305Y181160D01*
X502785Y169300D01*
X497567Y161266D01*
X481509Y85717D01*
X486038Y64409D01*
X483258Y51330D01*
Y42801D01*
G03X485320Y40739I2062J0D01*
G01X486696D01*
G02X487402Y40033I0J-706D01*
G01Y38583D01*
G01X502575Y199382D02*
Y198798D01*
X503642Y197154D01*
X507195Y194846D01*
X508282Y194615D01*
X512325Y191993D01*
X513538Y190123D01*
X515006Y183223D01*
X514505Y180716D01*
X515082Y179827D01*
X514833Y178653D01*
X513943Y178075D01*
X492382Y76628D01*
X494234Y67914D01*
X491546Y55253D01*
Y47524D01*
G03X492407Y46663I861J0D01*
G01X493783D01*
G03X494489Y47369I0J706D01*
G01Y48819D01*
G01Y43307D02*
Y44757D01*
G03X493783Y45463I-706J0D01*
G01X492407D01*
G02X490346Y47524I0J2061D01*
G01Y55379D01*
X491675Y61645D01*
X491676D01*
X493007Y67914D01*
X491155Y76628D01*
X512872Y178811D01*
X513232Y180472D01*
X513780Y183215D01*
X512410Y189657D01*
X511935Y190390D01*
X511457Y191125D01*
X509637Y192305D01*
X507815Y193487D01*
X506728Y193718D01*
X502774Y196286D01*
X501375Y198442D01*
Y199382D01*
G01X509187Y199425D02*
X510474D01*
X513976Y195924D01*
X517261Y195226D01*
X522568Y191779D01*
X523656Y190104D01*
X525047Y183556D01*
X498632Y59279D01*
Y42800D01*
G03X499493Y41939I861J0D01*
G01X500869D01*
G03X501575Y42645I0J706D01*
G01Y44095D01*
G01X509187Y198225D02*
X509976D01*
X513378Y194823D01*
X516794Y194098D01*
X521700Y190911D01*
X522528Y189637D01*
X523820Y183556D01*
X497432Y59406D01*
Y42800D01*
G03X499493Y40739I2061J0D01*
G01X500869D01*
G02X501575Y40033I0J-706D01*
G01Y38583D01*
G01X517608Y245465D02*
X518008D01*
X518700Y244773D01*
Y214502D01*
X520448Y206279D01*
X531190Y189738D01*
X534022Y176411D01*
X511605Y70929D01*
Y64764D01*
X510855Y64014D01*
Y62814D01*
X511605Y62064D01*
Y60864D01*
X510855Y60114D01*
Y58914D01*
X511605Y58164D01*
Y42800D01*
G03X513666Y40739I2061J0D01*
G01X515042D01*
G02X515748Y40033I0J-706D01*
G01Y38583D01*
G01X518087Y258475D02*
X519311D01*
X524240Y253546D01*
Y251986D01*
X527714Y248512D01*
Y218382D01*
X543412Y194207D01*
X547159Y176578D01*
X534514Y117079D01*
X539991Y91305D01*
X534065Y63430D01*
Y47524D01*
G03X534926Y46663I861J0D01*
G01X536302D01*
G03X537008Y47369I0J706D01*
G01Y48819D01*
G01X518087Y257275D02*
X518813D01*
X523040Y253048D01*
Y251488D01*
X526514Y248014D01*
Y218026D01*
X532397Y208964D01*
X532177Y207927D01*
X532830Y206920D01*
X533868Y206700D01*
X534521Y205693D01*
X534301Y204656D01*
X534954Y203649D01*
X535991Y203429D01*
X542285Y193733D01*
X545932Y176578D01*
X533287Y117079D01*
X538764Y91305D01*
X532865Y63557D01*
Y47524D01*
G03X534926Y45463I2061J0D01*
G01X536302D01*
G02X537008Y44757I0J-706D01*
G01Y43307D01*
G01X516887Y270285D02*
X517715D01*
X529300Y258700D01*
X532098D01*
X537442Y253356D01*
Y233754D01*
X538578Y228412D01*
X547444Y214763D01*
X549462Y205270D01*
X551433Y195996D01*
X555429Y177197D01*
X543536Y121248D01*
X551763Y82529D01*
X548238Y65939D01*
Y47524D01*
G03X549099Y46663I861J0D01*
G01X550475D01*
G03X551181Y47369I0J706D01*
G01Y48819D01*
G01X516887Y269085D02*
X517217D01*
X518066Y268236D01*
Y267176D01*
X518914Y266327D01*
X519975D01*
X520823Y265479D01*
Y264418D01*
X521672Y263570D01*
X522732D01*
X528802Y257500D01*
X531600D01*
X536242Y252858D01*
Y233627D01*
X537450Y227945D01*
X546316Y214296D01*
X554202Y177197D01*
X542309Y121248D01*
X550536Y82529D01*
X547038Y66066D01*
Y47524D01*
G03X549099Y45463I2061J0D01*
G01X550475D01*
G02X551181Y44757I0J-706D01*
G01Y43307D01*
G01X522835Y48819D02*
Y47369D01*
G02X522129Y46663I-706J0D01*
G01X520753D01*
G02X519892Y47524I0J861D01*
G01Y68255D01*
X526481Y99252D01*
X524508Y108533D01*
X539135Y177352D01*
X536250Y190925D01*
X526125Y206517D01*
X526124Y206518D01*
X524284Y209352D01*
X522500Y217742D01*
Y246473D01*
X518378Y250595D01*
X517121D01*
G01Y249395D02*
X517880D01*
X521300Y245975D01*
Y217615D01*
X523156Y208885D01*
X524565Y206714D01*
X524345Y205677D01*
X524998Y204670D01*
X526036Y204449D01*
X526689Y203443D01*
X526690D01*
X526469Y202406D01*
X527123Y201400D01*
X528160Y201179D01*
X535122Y190458D01*
X537908Y177352D01*
X523281Y108533D01*
X525254Y99252D01*
X518692Y68382D01*
Y47524D01*
G03X520753Y45463I2061J0D01*
G01X522129D01*
G02X522835Y44757I0J-706D01*
G01Y43307D01*
G01X517554Y278157D02*
X520097D01*
X532554Y265700D01*
X546264D01*
X560771Y256284D01*
X564037Y251252D01*
X566224Y240962D01*
X558224Y202143D01*
X563914Y175372D01*
X553133Y124651D01*
X563914Y73919D01*
X562412Y66853D01*
Y47524D01*
G03X563273Y46663I861J0D01*
G01X564649D01*
G03X565355Y47369I0J706D01*
G01Y48819D01*
G01Y43307D02*
Y44757D01*
G03X564649Y45463I-706J0D01*
G01X563273D01*
G02X561212Y47524I0J2061D01*
G01Y66980D01*
X562687Y73919D01*
X551906Y124651D01*
X562687Y175372D01*
X556997Y202139D01*
X564997Y240958D01*
X562909Y250785D01*
X559903Y255416D01*
X556013Y257941D01*
X554975Y257720D01*
X553969Y258373D01*
X553748Y259411D01*
X552741Y260064D01*
X551704Y259844D01*
X550697Y260497D01*
X550477Y261534D01*
X545908Y264500D01*
X532056D01*
X519599Y276957D01*
X517193D01*
G01X517139Y286028D02*
X521628D01*
X530056Y277600D01*
X547251D01*
X565724Y265601D01*
X571849Y256170D01*
X575565Y238679D01*
X567047Y198614D01*
X572842Y171366D01*
X563131Y125686D01*
X576585Y62393D01*
Y47524D01*
G03X577446Y46663I861J0D01*
G01X578822D01*
G03X579528Y47369I0J706D01*
G01Y48819D01*
G01X517500Y284828D02*
X521130D01*
X529558Y276400D01*
X546895D01*
X553244Y272275D01*
X553465Y271238D01*
X554471Y270584D01*
X555509Y270805D01*
X556515Y270151D01*
X556736Y269113D01*
X557742Y268459D01*
X558779Y268680D01*
X564856Y264733D01*
X570721Y255703D01*
X574338Y238679D01*
X565820Y198614D01*
X571615Y171366D01*
X561904Y125686D01*
X575385Y62266D01*
Y47524D01*
G03X577446Y45463I2061J0D01*
G01X578822D01*
G02X579528Y44757I0J-706D01*
G01Y43307D01*
G01X516209Y263300D02*
X519271D01*
X527001Y255570D01*
Y253187D01*
X530620Y249568D01*
Y238324D01*
X534624Y234320D01*
Y233294D01*
X535248Y228747D01*
X535872Y224202D01*
X543584Y212330D01*
X551541Y174884D01*
X539283Y117192D01*
X546331Y84027D01*
X541151Y59657D01*
Y42801D01*
G03X542013Y41939I862J0D01*
G01X543389D01*
G03X544095Y42645I0J706D01*
G01Y44095D01*
G01X516209Y262100D02*
X518773D01*
X525801Y255072D01*
Y252689D01*
X529420Y249070D01*
Y237826D01*
X533424Y233822D01*
Y233212D01*
X533747Y230858D01*
X534719Y223773D01*
X536082Y221675D01*
X535862Y220637D01*
X536516Y219631D01*
X537553Y219410D01*
X538207Y218404D01*
X537987Y217367D01*
X538640Y216360D01*
X539678Y216140D01*
X539677D01*
X542456Y211863D01*
X550314Y174884D01*
X538056Y117192D01*
X545104Y84027D01*
X539951Y59784D01*
Y42801D01*
G03X542013Y40739I2062J0D01*
G01X543389D01*
G02X544095Y40033I0J-706D01*
G01Y38583D01*
G01X517608Y246665D02*
X518506D01*
X519900Y245271D01*
Y214629D01*
X521576Y206746D01*
X532318Y190205D01*
X535249Y176411D01*
X512805Y70802D01*
Y42800D01*
G03X513666Y41939I861J0D01*
G01X515042D01*
G03X515748Y42645I0J706D01*
G01Y44095D01*
G01X517464Y274295D02*
X518705D01*
X530800Y262200D01*
X532800D01*
X540281Y254719D01*
Y235575D01*
X540817Y233055D01*
X541432Y232107D01*
X541433D01*
X542046Y231161D01*
X542047Y231162D01*
X550692Y217838D01*
X560035Y173884D01*
X548834Y121181D01*
X558092Y77606D01*
X555324Y64580D01*
Y42801D01*
G03X556186Y41939I862J0D01*
G01X557562D01*
G03X558268Y42645I0J706D01*
G01Y44095D01*
G01X517464Y273095D02*
X518207D01*
X530302Y261000D01*
X532302D01*
X539081Y254221D01*
Y235448D01*
X539689Y232588D01*
X541039Y230508D01*
X540818Y229471D01*
X541471Y228464D01*
X542508Y228243D01*
X543162Y227237D01*
X542941Y226199D01*
X543594Y225193D01*
X544631Y224972D01*
X549564Y217371D01*
X558808Y173884D01*
X547607Y121181D01*
X556865Y77606D01*
X554124Y64707D01*
Y42801D01*
G03X556186Y40739I2062J0D01*
G01X557562D01*
G02X558268Y40033I0J-706D01*
G01Y38583D01*
G01X518065Y254535D02*
X518963D01*
X521422Y252076D01*
Y251225D01*
X525038Y247609D01*
Y218300D01*
X525920Y214154D01*
X529257Y209013D01*
X539753Y192850D01*
X542899Y178048D01*
X529422Y114621D01*
X533246Y96632D01*
X526978Y67154D01*
Y42801D01*
G03X527840Y41939I862J0D01*
G01X529216D01*
G03X529922Y42645I0J706D01*
G01Y44095D01*
G01Y38583D02*
Y40033D01*
G03X529216Y40739I-706J0D01*
G01X527840D01*
G02X525778Y42801I0J2062D01*
G01Y67281D01*
X528897Y81955D01*
X528898D01*
X532019Y96632D01*
X528195Y114621D01*
X541672Y178048D01*
X538626Y192379D01*
X533146Y200819D01*
X532108Y201040D01*
X531455Y202046D01*
X531675Y203084D01*
X531022Y204090D01*
X531023D01*
X529985Y204310D01*
X529332Y205317D01*
X529552Y206354D01*
X524792Y213687D01*
X523838Y218173D01*
Y247111D01*
X520222Y250727D01*
Y251578D01*
X518465Y253335D01*
X518065D01*
G01X572441Y44095D02*
Y42645D01*
G02X571735Y41939I-706J0D01*
G01X570359D01*
G02X569498Y42800I0J861D01*
G01Y72841D01*
X558500Y124587D01*
X568469Y171488D01*
X562463Y199742D01*
X570679Y238398D01*
X567161Y254959D01*
X563593Y260455D01*
X552932Y267375D01*
Y267376D01*
X546425Y271600D01*
X530718D01*
X520215Y282103D01*
X517198D01*
G01X572441Y38583D02*
Y40033D01*
G03X571735Y40739I-706J0D01*
G01X570359D01*
G02X568298Y42800I0J2061D01*
G01Y72714D01*
X557273Y124587D01*
X567242Y171488D01*
X561236Y199742D01*
X569452Y238398D01*
X566033Y254492D01*
X562725Y259587D01*
X552695Y266098D01*
X551658Y265878D01*
X550651Y266531D01*
X550430Y267569D01*
X549424Y268222D01*
X548387Y268001D01*
X547381Y268654D01*
X547160Y269692D01*
X546069Y270400D01*
X530220D01*
X519717Y280903D01*
X517559D01*
G01X513254Y289787D02*
Y291152D01*
X514602Y292500D01*
X521381D01*
X529881Y284000D01*
X548051D01*
X568949Y270434D01*
X576333Y259066D01*
X580556Y239184D01*
X571501Y196588D01*
X576992Y170752D01*
X567844Y127711D01*
X583671Y53250D01*
Y42800D01*
G03X584532Y41939I861J0D01*
G01X585908D01*
G03X586614Y42645I0J706D01*
G01Y44095D01*
G01X514454Y289787D02*
Y290654D01*
X515100Y291300D01*
X520883D01*
X529383Y282800D01*
X547695D01*
X554439Y278422D01*
X554659Y277385D01*
X555666Y276732D01*
X556703Y276952D01*
X557710Y276299D01*
X557931Y275261D01*
X558937Y274608D01*
X559974Y274828D01*
X560981Y274175D01*
X561201Y273138D01*
X562208Y272485D01*
X563245Y272705D01*
X568081Y269566D01*
X575205Y258599D01*
X579329Y239184D01*
X570274Y196588D01*
X575765Y170752D01*
X566617Y127711D01*
X582471Y53123D01*
Y42800D01*
G03X584532Y40739I2061J0D01*
G01X585908D01*
G02X586614Y40033I0J-706D01*
G01Y38583D01*
G54D19*
G01X121778Y-377522D02*
X122652Y-376647D01*
X123307Y-375189D01*
X123744Y-373146D01*
X123307Y-371397D01*
X122434Y-370230D01*
X120905Y-369355D01*
X115010D01*
Y-386855D01*
X122215D01*
X123744Y-385689D01*
X124617Y-383938D01*
X125054Y-381897D01*
X124617Y-379855D01*
X123307Y-378105D01*
X121778Y-377522D01*
X115010D01*
G01X134475Y-386855D02*
Y-375189D01*
G01Y-377522D02*
X135567Y-376355D01*
X136659Y-375480D01*
X138187Y-375189D01*
X139278Y-375480D01*
X140589Y-376355D01*
G01X150447Y-392105D02*
X151757Y-392688D01*
X153504Y-392105D01*
X154595Y-390939D01*
X155469Y-389480D01*
X156778Y-384814D01*
X159617Y-375189D01*
G01X152630D02*
X156778Y-384814D01*
G01X176025Y-376647D02*
X174497Y-375480D01*
X173187Y-375189D01*
X171440Y-375772D01*
X170130Y-376938D01*
X169257Y-378980D01*
X169038Y-381022D01*
X169257Y-383064D01*
X170130Y-384814D01*
X171440Y-386272D01*
X173187Y-386855D01*
X174715Y-386272D01*
X176025Y-385105D01*
G01X186757Y-378980D02*
X193744D01*
X193089Y-376938D01*
X191997Y-375772D01*
X190469Y-375189D01*
X188940Y-375480D01*
X187630Y-376355D01*
X186757Y-378397D01*
X186320Y-380147D01*
Y-381897D01*
X186757Y-383647D01*
X187849Y-385397D01*
X189159Y-386563D01*
X190687Y-386855D01*
X192215Y-386272D01*
X193744Y-384522D01*
G01X229835Y-370814D02*
X228525Y-369938D01*
X226997Y-369355D01*
X225250D01*
X223285Y-370230D01*
X221757Y-371688D01*
X220665Y-373439D01*
X219792Y-376355D01*
X219573Y-378980D01*
X220010Y-381605D01*
X220665Y-383355D01*
X221975Y-385105D01*
X223504Y-386272D01*
X225032Y-386855D01*
X226560D01*
X228089Y-386272D01*
X229399Y-385397D01*
X230491Y-384231D01*
G01X246462Y-386855D02*
Y-375189D01*
G01Y-377230D02*
X245589Y-376064D01*
X244278Y-375480D01*
X242750Y-375189D01*
X241222Y-375772D01*
X239912Y-376938D01*
X239038Y-378688D01*
X238602Y-381022D01*
X239038Y-383355D01*
X239912Y-385105D01*
X241222Y-386272D01*
X242750Y-386855D01*
X244278Y-386563D01*
X245589Y-385689D01*
X246462Y-384522D01*
G01X256320Y-386855D02*
Y-375189D01*
G01Y-378105D02*
X257194Y-376647D01*
X258504Y-375480D01*
X260250Y-375189D01*
X261778Y-375480D01*
X263089Y-376647D01*
X263744Y-378688D01*
Y-386855D01*
G01X272947Y-392105D02*
X274257Y-392688D01*
X276004Y-392105D01*
X277095Y-390939D01*
X277969Y-389480D01*
X279278Y-384814D01*
X282117Y-375189D01*
G01X275130D02*
X279278Y-384814D01*
G01X295032Y-386855D02*
X293722Y-386563D01*
X292412Y-385397D01*
X291538Y-383355D01*
X291102Y-381022D01*
X291538Y-378688D01*
X292412Y-376647D01*
X293722Y-375480D01*
X295032Y-375189D01*
X296342Y-375480D01*
X297652Y-376647D01*
X298525Y-378688D01*
X298744Y-381022D01*
X298525Y-383355D01*
X297652Y-385397D01*
X296342Y-386563D01*
X295032Y-386855D01*
G01X308820D02*
Y-375189D01*
G01Y-378105D02*
X309694Y-376647D01*
X311004Y-375480D01*
X312750Y-375189D01*
X314278Y-375480D01*
X315589Y-376647D01*
X316244Y-378688D01*
Y-386855D01*
G01X342947Y-384522D02*
X344694Y-385980D01*
X346659Y-386855D01*
X348405D01*
X350152Y-385980D01*
X351462Y-384522D01*
X352117Y-382480D01*
X351680Y-380439D01*
X350589Y-378688D01*
X348624Y-377522D01*
X346004Y-376938D01*
X344475Y-375772D01*
X343820Y-373730D01*
X344257Y-371688D01*
X345349Y-370230D01*
X346877Y-369355D01*
X348405D01*
X349934Y-369938D01*
X351244Y-371397D01*
G01X369835Y-370814D02*
X368525Y-369938D01*
X366997Y-369355D01*
X365250D01*
X363285Y-370230D01*
X361757Y-371688D01*
X360665Y-373439D01*
X359792Y-376355D01*
X359573Y-378980D01*
X360010Y-381605D01*
X360665Y-383355D01*
X361975Y-385105D01*
X363504Y-386272D01*
X365032Y-386855D01*
X366560D01*
X368089Y-386272D01*
X369399Y-385397D01*
X370491Y-384231D01*
G01X387335Y-370814D02*
X386025Y-369938D01*
X384497Y-369355D01*
X382750D01*
X380785Y-370230D01*
X379257Y-371688D01*
X378165Y-373439D01*
X377292Y-376355D01*
X377073Y-378980D01*
X377510Y-381605D01*
X378165Y-383355D01*
X379475Y-385105D01*
X381004Y-386272D01*
X382532Y-386855D01*
X384060D01*
X385589Y-386272D01*
X386899Y-385397D01*
X387991Y-384231D01*
G01X210605Y-341855D02*
Y-324355D01*
X216282Y-338938D01*
X221959Y-324355D01*
Y-341855D01*
G01X233782D02*
X232472Y-341563D01*
X231162Y-340397D01*
X230288Y-338355D01*
X229852Y-336022D01*
X230288Y-333688D01*
X231162Y-331647D01*
X232472Y-330480D01*
X233782Y-330189D01*
X235092Y-330480D01*
X236402Y-331647D01*
X237275Y-333688D01*
X237494Y-336022D01*
X237275Y-338355D01*
X236402Y-340397D01*
X235092Y-341563D01*
X233782Y-341855D01*
G01X255212Y-324355D02*
Y-341855D01*
G01Y-339231D02*
X254339Y-340689D01*
X253028Y-341563D01*
X251500Y-341855D01*
X249754Y-341272D01*
X248444Y-339814D01*
X247570Y-338064D01*
X247352Y-336022D01*
X247570Y-333980D01*
X248444Y-332230D01*
X249754Y-330772D01*
X251500Y-330189D01*
X253028Y-330480D01*
X254120Y-331064D01*
X255212Y-332230D01*
G01X265507Y-333980D02*
X272494D01*
X271839Y-331938D01*
X270747Y-330772D01*
X269219Y-330189D01*
X267690Y-330480D01*
X266380Y-331355D01*
X265507Y-333397D01*
X265070Y-335147D01*
Y-336897D01*
X265507Y-338647D01*
X266599Y-340397D01*
X267909Y-341563D01*
X269437Y-341855D01*
X270965Y-341272D01*
X272494Y-339522D01*
G01X286282Y-341855D02*
Y-324355D01*
G01X566882Y-386855D02*
Y-369355D01*
X564262Y-372855D01*
G01Y-386855D02*
X569502D01*
G01X580234Y-379564D02*
X581762Y-377522D01*
X583072Y-376355D01*
X584819Y-375772D01*
X586347Y-376355D01*
X587439Y-377522D01*
X588312Y-379272D01*
X588530Y-381313D01*
X588312Y-383064D01*
X587439Y-384814D01*
X586128Y-386272D01*
X584600Y-386855D01*
X582854Y-386272D01*
X581325Y-384522D01*
X580452Y-381897D01*
X580234Y-378980D01*
X580670Y-375189D01*
X581325Y-373146D01*
X582417Y-371105D01*
X583945Y-369647D01*
X585474Y-369355D01*
X587002Y-369938D01*
X588094Y-371397D01*
G01X597079Y-383355D02*
X598388Y-385397D01*
X600135Y-386563D01*
X602100Y-386855D01*
X603847Y-386563D01*
X605594Y-385105D01*
X606685Y-383355D01*
X606904Y-381605D01*
X606467Y-379564D01*
X604939Y-378105D01*
X603410Y-377522D01*
X601445D01*
G01X603410D02*
X604720Y-376647D01*
X605812Y-375189D01*
X606249Y-373439D01*
X605812Y-371688D01*
X604720Y-370230D01*
X602755Y-369355D01*
X600790Y-369647D01*
X598825Y-370814D01*
G01X619382Y-386855D02*
Y-369355D01*
X616762Y-372855D01*
G01Y-386855D02*
X622002D01*
G01X632734Y-379564D02*
X634262Y-377522D01*
X635572Y-376355D01*
X637319Y-375772D01*
X638847Y-376355D01*
X639939Y-377522D01*
X640812Y-379272D01*
X641030Y-381313D01*
X640812Y-383064D01*
X639939Y-384814D01*
X638628Y-386272D01*
X637100Y-386855D01*
X635354Y-386272D01*
X633825Y-384522D01*
X632952Y-381897D01*
X632734Y-378980D01*
X633170Y-375189D01*
X633825Y-373146D01*
X634917Y-371105D01*
X636445Y-369647D01*
X637974Y-369355D01*
X639502Y-369938D01*
X640594Y-371397D01*
G01X553765Y-341855D02*
Y-324355D01*
X559005D01*
X560752Y-325230D01*
X562062Y-327272D01*
X562499Y-329605D01*
X562062Y-331938D01*
X560970Y-333688D01*
X559005Y-334564D01*
X553765D01*
G01X580435Y-325814D02*
X579125Y-324938D01*
X577597Y-324355D01*
X575850D01*
X573885Y-325230D01*
X572357Y-326688D01*
X571265Y-328439D01*
X570392Y-331355D01*
X570173Y-333980D01*
X570610Y-336605D01*
X571265Y-338355D01*
X572575Y-340105D01*
X574104Y-341272D01*
X575632Y-341855D01*
X577160D01*
X578689Y-341272D01*
X579999Y-340397D01*
X581091Y-339231D01*
G01X594878Y-332522D02*
X595752Y-331647D01*
X596407Y-330189D01*
X596844Y-328146D01*
X596407Y-326397D01*
X595534Y-325230D01*
X594005Y-324355D01*
X588110D01*
Y-341855D01*
X595315D01*
X596844Y-340689D01*
X597717Y-338938D01*
X598154Y-336897D01*
X597717Y-334855D01*
X596407Y-333105D01*
X594878Y-332522D01*
X588110D01*
G01X604082Y-347688D02*
X617182D01*
G01X623110Y-341855D02*
Y-324355D01*
X633154Y-341855D01*
Y-324355D01*
G01X645632Y-341855D02*
X643885Y-341563D01*
X642357Y-340397D01*
X641047Y-338647D01*
X640173Y-336605D01*
X639737Y-334272D01*
Y-331938D01*
X640173Y-329605D01*
X641047Y-327563D01*
X642357Y-325814D01*
X643885Y-324647D01*
X645632Y-324355D01*
X647378Y-324647D01*
X648907Y-325814D01*
X650217Y-327563D01*
X651091Y-329605D01*
X651527Y-331938D01*
Y-334272D01*
X651091Y-336605D01*
X650217Y-338647D01*
X648907Y-340397D01*
X647378Y-341563D01*
X645632Y-341855D01*
G01X696473Y-324355D02*
X701932Y-341855D01*
X707391Y-324355D01*
G01X723799Y-341855D02*
X715065D01*
Y-324355D01*
X723799D01*
G01X720305Y-332813D02*
X715065D01*
G01X732565Y-341855D02*
Y-324355D01*
X738024D01*
X739770Y-325230D01*
X740862Y-326397D01*
X741299Y-328730D01*
X740862Y-331064D01*
X739552Y-332522D01*
X738024Y-333397D01*
X732565D01*
G01X738024D02*
X741299Y-341855D01*
G01X754432Y-342438D02*
X753995Y-342147D01*
Y-341563D01*
X754432Y-341272D01*
X754869Y-341563D01*
Y-342147D01*
X754432Y-342438D01*
G01X728182Y-386855D02*
Y-369355D01*
X725562Y-372855D01*
G01Y-386855D02*
X730802D01*
G01X882499Y-369355D02*
Y-386855D01*
X873765D01*
G01X864780Y-379564D02*
X863252Y-377522D01*
X861942Y-376355D01*
X860195Y-375772D01*
X858667Y-376355D01*
X857575Y-377522D01*
X856702Y-379272D01*
X856484Y-381313D01*
X856702Y-383064D01*
X857575Y-384814D01*
X858886Y-386272D01*
X860414Y-386855D01*
X862160Y-386272D01*
X863689Y-384522D01*
X864562Y-381897D01*
X864780Y-378980D01*
X864344Y-375189D01*
X863689Y-373146D01*
X862597Y-371105D01*
X861069Y-369647D01*
X859540Y-369355D01*
X858012Y-369938D01*
X856920Y-371397D01*
G01X830015Y-324355D02*
Y-341855D01*
X838749D01*
G01X855812D02*
Y-330189D01*
G01Y-332230D02*
X854939Y-331064D01*
X853628Y-330480D01*
X852100Y-330189D01*
X850572Y-330772D01*
X849262Y-331938D01*
X848388Y-333688D01*
X847952Y-336022D01*
X848388Y-338355D01*
X849262Y-340105D01*
X850572Y-341272D01*
X852100Y-341855D01*
X853628Y-341563D01*
X854939Y-340689D01*
X855812Y-339522D01*
G01X864797Y-347105D02*
X866107Y-347688D01*
X867854Y-347105D01*
X868945Y-345939D01*
X869819Y-344480D01*
X871128Y-339814D01*
X873967Y-330189D01*
G01X866980D02*
X871128Y-339814D01*
G01X883607Y-333980D02*
X890594D01*
X889939Y-331938D01*
X888847Y-330772D01*
X887319Y-330189D01*
X885790Y-330480D01*
X884480Y-331355D01*
X883607Y-333397D01*
X883170Y-335147D01*
Y-336897D01*
X883607Y-338647D01*
X884699Y-340397D01*
X886009Y-341563D01*
X887537Y-341855D01*
X889065Y-341272D01*
X890594Y-339522D01*
G01X901325Y-341855D02*
Y-330189D01*
G01Y-332522D02*
X902417Y-331355D01*
X903509Y-330480D01*
X905037Y-330189D01*
X906128Y-330480D01*
X907439Y-331355D01*
G01X994432Y-386855D02*
X992685Y-386563D01*
X991157Y-385397D01*
X989847Y-383647D01*
X988973Y-381605D01*
X988537Y-379272D01*
Y-376938D01*
X988973Y-374605D01*
X989847Y-372563D01*
X991157Y-370814D01*
X992685Y-369647D01*
X994432Y-369355D01*
X996178Y-369647D01*
X997707Y-370814D01*
X999017Y-372563D01*
X999891Y-374605D01*
X1000327Y-376938D01*
Y-379272D01*
X999891Y-381605D01*
X999017Y-383647D01*
X997707Y-385397D01*
X996178Y-386563D01*
X994432Y-386855D01*
G01X996178Y-382188D02*
X998799Y-386855D01*
G01X1007129Y-369355D02*
Y-381897D01*
X1008002Y-384522D01*
X1009749Y-386272D01*
X1011932Y-386855D01*
X1014115Y-386272D01*
X1015862Y-384522D01*
X1016735Y-381897D01*
Y-369355D01*
G01X1026812D02*
X1032052D01*
G01X1029432D02*
Y-386855D01*
G01X1026812D02*
X1032052D01*
G01X1041910D02*
Y-369355D01*
X1051954Y-386855D01*
Y-369355D01*
G01X1069235Y-370814D02*
X1067925Y-369938D01*
X1066397Y-369355D01*
X1064650D01*
X1062685Y-370230D01*
X1061157Y-371688D01*
X1060065Y-373439D01*
X1059192Y-376355D01*
X1058973Y-378980D01*
X1059410Y-381605D01*
X1060065Y-383355D01*
X1061375Y-385105D01*
X1062904Y-386272D01*
X1064432Y-386855D01*
X1065960D01*
X1067489Y-386272D01*
X1068799Y-385397D01*
X1069891Y-384231D01*
G01X1081932Y-386855D02*
Y-378980D01*
X1077565Y-369355D01*
G01X1086299D02*
X1081932Y-378980D01*
G01X972129Y-341855D02*
Y-324355D01*
X976495D01*
X978242Y-325230D01*
X979552Y-326397D01*
X980644Y-328146D01*
X981517Y-330189D01*
X981735Y-333105D01*
X981517Y-336022D01*
X980644Y-338064D01*
X979552Y-339814D01*
X978242Y-340980D01*
X976495Y-341855D01*
X972129D01*
G01X991157Y-333980D02*
X998144D01*
X997489Y-331938D01*
X996397Y-330772D01*
X994869Y-330189D01*
X993340Y-330480D01*
X992030Y-331355D01*
X991157Y-333397D01*
X990720Y-335147D01*
Y-336897D01*
X991157Y-338647D01*
X992249Y-340397D01*
X993559Y-341563D01*
X995087Y-341855D01*
X996615Y-341272D01*
X998144Y-339522D01*
G01X1008657Y-339814D02*
X1009749Y-340980D01*
X1011277Y-341855D01*
X1012587D01*
X1013897Y-341272D01*
X1014770Y-340397D01*
X1015207Y-339231D01*
X1014989Y-337480D01*
X1014115Y-336605D01*
X1010185Y-334855D01*
X1009312Y-332813D01*
X1009749Y-331355D01*
X1010622Y-330480D01*
X1011932Y-330189D01*
X1013242Y-330480D01*
X1014552Y-331355D01*
G01X1029432Y-330189D02*
Y-341855D01*
G01Y-325522D02*
X1028995Y-325230D01*
Y-324647D01*
X1029432Y-324355D01*
X1029869Y-324647D01*
Y-325230D01*
X1029432Y-325522D01*
G01X1043875Y-346230D02*
X1045404Y-347397D01*
X1047150Y-347688D01*
X1048678Y-347397D01*
X1049989Y-345939D01*
X1050862Y-343897D01*
Y-330189D01*
G01Y-332522D02*
X1049989Y-331355D01*
X1048678Y-330480D01*
X1047150Y-330189D01*
X1045404Y-330772D01*
X1044312Y-331938D01*
X1043438Y-333980D01*
X1043002Y-336022D01*
X1043220Y-337772D01*
X1044094Y-339814D01*
X1045404Y-341272D01*
X1047150Y-341855D01*
X1048460Y-341563D01*
X1049989Y-340397D01*
X1050862Y-339231D01*
G01X1060720Y-341855D02*
Y-330189D01*
G01Y-333105D02*
X1061594Y-331647D01*
X1062904Y-330480D01*
X1064650Y-330189D01*
X1066178Y-330480D01*
X1067489Y-331647D01*
X1068144Y-333688D01*
Y-341855D01*
G01X1078657Y-333980D02*
X1085644D01*
X1084989Y-331938D01*
X1083897Y-330772D01*
X1082369Y-330189D01*
X1080840Y-330480D01*
X1079530Y-331355D01*
X1078657Y-333397D01*
X1078220Y-335147D01*
Y-336897D01*
X1078657Y-338647D01*
X1079749Y-340397D01*
X1081059Y-341563D01*
X1082587Y-341855D01*
X1084115Y-341272D01*
X1085644Y-339522D01*
G01X1096375Y-341855D02*
Y-330189D01*
G01Y-332522D02*
X1097467Y-331355D01*
X1098559Y-330480D01*
X1100087Y-330189D01*
X1101178Y-330480D01*
X1102489Y-331355D01*
G01X1143132Y-369355D02*
X1141385Y-369938D01*
X1140075Y-371397D01*
X1139202Y-373146D01*
X1138547Y-375480D01*
X1138329Y-378105D01*
X1138547Y-380730D01*
X1139202Y-383064D01*
X1140075Y-384814D01*
X1141385Y-386272D01*
X1143132Y-386855D01*
X1144878Y-386272D01*
X1146189Y-384814D01*
X1147062Y-383064D01*
X1147717Y-380730D01*
X1147935Y-378105D01*
X1147717Y-375480D01*
X1147062Y-373146D01*
X1146189Y-371397D01*
X1144878Y-369938D01*
X1143132Y-369355D01*
G01X1156484Y-379564D02*
X1158012Y-377522D01*
X1159322Y-376355D01*
X1161069Y-375772D01*
X1162597Y-376355D01*
X1163689Y-377522D01*
X1164562Y-379272D01*
X1164780Y-381313D01*
X1164562Y-383064D01*
X1163689Y-384814D01*
X1162378Y-386272D01*
X1160850Y-386855D01*
X1159104Y-386272D01*
X1157575Y-384522D01*
X1156702Y-381897D01*
X1156484Y-378980D01*
X1156920Y-375189D01*
X1157575Y-373146D01*
X1158667Y-371105D01*
X1160195Y-369647D01*
X1161724Y-369355D01*
X1163252Y-369938D01*
X1164344Y-371397D01*
G01X1174202Y-387438D02*
X1182062Y-369355D01*
G01X1191484Y-372272D02*
X1192794Y-370522D01*
X1194322Y-369647D01*
X1196069Y-369355D01*
X1198252Y-369938D01*
X1199780Y-371397D01*
X1200217Y-373146D01*
X1199999Y-374897D01*
X1199125Y-376355D01*
X1194759Y-379272D01*
X1192794Y-381313D01*
X1191484Y-384231D01*
X1191047Y-386855D01*
X1200217D01*
G01X1213132D02*
Y-369355D01*
X1210512Y-372855D01*
G01Y-386855D02*
X1215752D01*
G01X1226702Y-387438D02*
X1234562Y-369355D01*
G01X1243984Y-372272D02*
X1245294Y-370522D01*
X1246822Y-369647D01*
X1248569Y-369355D01*
X1250752Y-369938D01*
X1252280Y-371397D01*
X1252717Y-373146D01*
X1252499Y-374897D01*
X1251625Y-376355D01*
X1247259Y-379272D01*
X1245294Y-381313D01*
X1243984Y-384231D01*
X1243547Y-386855D01*
X1252717D01*
G01X1265632Y-369355D02*
X1263885Y-369938D01*
X1262575Y-371397D01*
X1261702Y-373146D01*
X1261047Y-375480D01*
X1260829Y-378105D01*
X1261047Y-380730D01*
X1261702Y-383064D01*
X1262575Y-384814D01*
X1263885Y-386272D01*
X1265632Y-386855D01*
X1267378Y-386272D01*
X1268689Y-384814D01*
X1269562Y-383064D01*
X1270217Y-380730D01*
X1270435Y-378105D01*
X1270217Y-375480D01*
X1269562Y-373146D01*
X1268689Y-371397D01*
X1267378Y-369938D01*
X1265632Y-369355D01*
G01X1283132Y-386855D02*
Y-369355D01*
X1280512Y-372855D01*
G01Y-386855D02*
X1285752D01*
G01X1300195D02*
X1300632Y-383064D01*
X1301287Y-379855D01*
X1302160Y-376938D01*
X1303252Y-373730D01*
X1304999Y-369355D01*
X1296265D01*
G01X1190829Y-341855D02*
Y-324355D01*
X1195195D01*
X1196942Y-325230D01*
X1198252Y-326397D01*
X1199344Y-328146D01*
X1200217Y-330189D01*
X1200435Y-333105D01*
X1200217Y-336022D01*
X1199344Y-338064D01*
X1198252Y-339814D01*
X1196942Y-340980D01*
X1195195Y-341855D01*
X1190829D01*
G01X1217062D02*
Y-330189D01*
G01Y-332230D02*
X1216189Y-331064D01*
X1214878Y-330480D01*
X1213350Y-330189D01*
X1211822Y-330772D01*
X1210512Y-331938D01*
X1209638Y-333688D01*
X1209202Y-336022D01*
X1209638Y-338355D01*
X1210512Y-340105D01*
X1211822Y-341272D01*
X1213350Y-341855D01*
X1214878Y-341563D01*
X1216189Y-340689D01*
X1217062Y-339522D01*
G01X1230632Y-324355D02*
Y-341855D01*
G01X1227575Y-330189D02*
X1233689D01*
G01X1244857Y-333980D02*
X1251844D01*
X1251189Y-331938D01*
X1250097Y-330772D01*
X1248569Y-330189D01*
X1247040Y-330480D01*
X1245730Y-331355D01*
X1244857Y-333397D01*
X1244420Y-335147D01*
Y-336897D01*
X1244857Y-338647D01*
X1245949Y-340397D01*
X1247259Y-341563D01*
X1248787Y-341855D01*
X1250315Y-341272D01*
X1251844Y-339522D01*
M02*
